FILE_TYPE = MACRO_DRAWING;
SET COLOR_WIRE YELLOW;
SET COLOR_PROP MONO;
SET COLOR_DOT WHITE;
SET COLOR_ARC YELLOW;
SET COLOR_BODY GREEN;
SET COLOR_NOTE MONO;
SET PROP_DISPLAY VALUE;
SET PAGE_NUMBER P68;
FORCEADD OFFPAGE..1
(-6925 3700);
FORCEPROP 2 LAST $XR0 34 
J 0
(-7146 3700);
DISPLAY 0.638298 (-7146 3700);
PAINT MONO (-7146 3700);
FORCEPROP 2 LAST CDS_LIB mstr_standard
J 0
(-6925 3700);
PAINT MONO (-6925 3700);
DISPLAY INVISIBLE (-6925 3700);
FORCEPROP 1 LAST OFFPAGE TRUE
J 0
(-6600 3575);
DISPLAY 1.170213 (-6600 3575);
PAINT GREEN (-6600 3575);
DISPLAY INVISIBLE (-6600 3575);
FORCEPROP 1 LAST COMMENT_BODY TRUE
J 0
(-6800 3600);
DISPLAY 1.170213 (-6800 3600);
PAINT GREEN (-6800 3600);
DISPLAY INVISIBLE (-6800 3600);
FORCEPROP 2 LAST PATH I1
J 0
(-6875 3775);
DISPLAY 1.021277 (-6875 3775);
PAINT ORANGE (-6875 3775);
DISPLAY INVISIBLE (-6875 3775);
FORCEADD TAP..1
R 2
(-5725 1900);
FORCEPROP 3 LASTPIN (-5675 1900) SIG_NAME UPI_CPU0_CPU1_P1P1_DN<5>
J 0
(-5665 1910);
DISPLAY 0.659574 (-5665 1910);
PAINT MONO (-5665 1910);
DISPLAY INVISIBLE (-5665 1910);
FORCEPROP 1 LASTPIN (-5675 1900) BN 5
J 2
(-5663 1908);
DISPLAY 0.617021 (-5663 1908);
PAINT GREEN (-5663 1908);
FORCEPROP 2 LAST CDS_LIB mstr_standard
J 0
(-5725 1900);
PAINT MONO (-5725 1900);
DISPLAY INVISIBLE (-5725 1900);
FORCEPROP 1 LAST BODY_TYPE PLUMBING
J 2
(-5725 1950);
DISPLAY 1.446809 (-5725 1950);
PAINT GREEN (-5725 1950);
DISPLAY INVISIBLE (-5725 1950);
FORCEPROP 1 LAST HDL_TAP TRUE
J 2
(-6050 1775);
DISPLAY 1.446809 (-6050 1775);
PAINT GREEN (-6050 1775);
DISPLAY INVISIBLE (-6050 1775);
FORCEPROP 1 LAST PATH I10
J 2
(-5723 1900);
DISPLAY 0.872340 (-5723 1900);
PAINT GREEN (-5723 1900);
DISPLAY INVISIBLE (-5723 1900);
FORCEADD TAP..1
(-2950 1700);
FORCEPROP 3 LASTPIN (-3000 1700) SIG_NAME UPI_CPU1_CPU0_P1P1_DP<1>
J 0
(-2990 1710);
DISPLAY 0.659574 (-2990 1710);
PAINT MONO (-2990 1710);
DISPLAY INVISIBLE (-2990 1710);
FORCEPROP 1 LASTPIN (-3000 1700) BN 1
J 0
(-3012 1708);
DISPLAY 0.617021 (-3012 1708);
PAINT GREEN (-3012 1708);
FORCEPROP 2 LAST CDS_LIB mstr_standard
J 0
(-2950 1700);
PAINT MONO (-2950 1700);
DISPLAY INVISIBLE (-2950 1700);
FORCEPROP 1 LAST BODY_TYPE PLUMBING
J 0
(-2950 1750);
DISPLAY 1.446809 (-2950 1750);
PAINT GREEN (-2950 1750);
DISPLAY INVISIBLE (-2950 1750);
FORCEPROP 1 LAST HDL_TAP TRUE
J 0
(-2625 1575);
DISPLAY 1.446809 (-2625 1575);
PAINT GREEN (-2625 1575);
DISPLAY INVISIBLE (-2625 1575);
FORCEPROP 1 LAST PATH I100
J 0
(-2952 1700);
DISPLAY 0.872340 (-2952 1700);
PAINT GREEN (-2952 1700);
DISPLAY INVISIBLE (-2952 1700);
FORCEADD TAP..1
(-2950 2950);
FORCEPROP 3 LASTPIN (-3000 2950) SIG_NAME UPI_CPU1_CPU0_P1P1_DP<5>
J 0
(-2990 2960);
DISPLAY 0.659574 (-2990 2960);
PAINT MONO (-2990 2960);
DISPLAY INVISIBLE (-2990 2960);
FORCEPROP 1 LASTPIN (-3000 2950) BN 5
J 0
(-3012 2958);
DISPLAY 0.617021 (-3012 2958);
PAINT GREEN (-3012 2958);
FORCEPROP 2 LAST CDS_LIB mstr_standard
J 0
(-2950 2950);
PAINT MONO (-2950 2950);
DISPLAY INVISIBLE (-2950 2950);
FORCEPROP 1 LAST BODY_TYPE PLUMBING
J 0
(-2950 3000);
DISPLAY 1.446809 (-2950 3000);
PAINT GREEN (-2950 3000);
DISPLAY INVISIBLE (-2950 3000);
FORCEPROP 1 LAST HDL_TAP TRUE
J 0
(-2625 2825);
DISPLAY 1.446809 (-2625 2825);
PAINT GREEN (-2625 2825);
DISPLAY INVISIBLE (-2625 2825);
FORCEPROP 1 LAST PATH I101
J 0
(-2952 2950);
DISPLAY 0.872340 (-2952 2950);
PAINT GREEN (-2952 2950);
DISPLAY INVISIBLE (-2952 2950);
FORCEADD TAP..1
(-2950 1950);
FORCEPROP 3 LASTPIN (-3000 1950) SIG_NAME UPI_CPU1_CPU0_P1P1_DP<6>
J 0
(-2990 1960);
DISPLAY 0.659574 (-2990 1960);
PAINT MONO (-2990 1960);
DISPLAY INVISIBLE (-2990 1960);
FORCEPROP 1 LASTPIN (-3000 1950) BN 6
J 0
(-3012 1958);
DISPLAY 0.617021 (-3012 1958);
PAINT GREEN (-3012 1958);
FORCEPROP 2 LAST CDS_LIB mstr_standard
J 0
(-2950 1950);
PAINT MONO (-2950 1950);
DISPLAY INVISIBLE (-2950 1950);
FORCEPROP 1 LAST BODY_TYPE PLUMBING
J 0
(-2950 2000);
DISPLAY 1.446809 (-2950 2000);
PAINT GREEN (-2950 2000);
DISPLAY INVISIBLE (-2950 2000);
FORCEPROP 1 LAST HDL_TAP TRUE
J 0
(-2625 1825);
DISPLAY 1.446809 (-2625 1825);
PAINT GREEN (-2625 1825);
DISPLAY INVISIBLE (-2625 1825);
FORCEPROP 1 LAST PATH I102
J 0
(-2952 1950);
DISPLAY 0.872340 (-2952 1950);
PAINT GREEN (-2952 1950);
DISPLAY INVISIBLE (-2952 1950);
FORCEADD TAP..1
(-2950 2000);
FORCEPROP 3 LASTPIN (-3000 2000) SIG_NAME UPI_CPU1_CPU0_P1P1_DP<7>
J 0
(-2990 2010);
DISPLAY 0.659574 (-2990 2010);
PAINT MONO (-2990 2010);
DISPLAY INVISIBLE (-2990 2010);
FORCEPROP 1 LASTPIN (-3000 2000) BN 7
J 0
(-3012 2008);
DISPLAY 0.617021 (-3012 2008);
PAINT GREEN (-3012 2008);
FORCEPROP 2 LAST CDS_LIB mstr_standard
J 0
(-2950 2000);
PAINT MONO (-2950 2000);
DISPLAY INVISIBLE (-2950 2000);
FORCEPROP 1 LAST BODY_TYPE PLUMBING
J 0
(-2950 2050);
DISPLAY 1.446809 (-2950 2050);
PAINT GREEN (-2950 2050);
DISPLAY INVISIBLE (-2950 2050);
FORCEPROP 1 LAST HDL_TAP TRUE
J 0
(-2625 1875);
DISPLAY 1.446809 (-2625 1875);
PAINT GREEN (-2625 1875);
DISPLAY INVISIBLE (-2625 1875);
FORCEPROP 1 LAST PATH I103
J 0
(-2952 2000);
DISPLAY 0.872340 (-2952 2000);
PAINT GREEN (-2952 2000);
DISPLAY INVISIBLE (-2952 2000);
FORCEADD TAP..1
(-2950 2050);
FORCEPROP 3 LASTPIN (-3000 2050) SIG_NAME UPI_CPU1_CPU0_P1P1_DP<8>
J 0
(-2990 2060);
DISPLAY 0.659574 (-2990 2060);
PAINT MONO (-2990 2060);
DISPLAY INVISIBLE (-2990 2060);
FORCEPROP 1 LASTPIN (-3000 2050) BN 8
J 0
(-3012 2058);
DISPLAY 0.617021 (-3012 2058);
PAINT GREEN (-3012 2058);
FORCEPROP 2 LAST CDS_LIB mstr_standard
J 0
(-2950 2050);
PAINT MONO (-2950 2050);
DISPLAY INVISIBLE (-2950 2050);
FORCEPROP 1 LAST BODY_TYPE PLUMBING
J 0
(-2950 2100);
DISPLAY 1.446809 (-2950 2100);
PAINT GREEN (-2950 2100);
DISPLAY INVISIBLE (-2950 2100);
FORCEPROP 1 LAST HDL_TAP TRUE
J 0
(-2625 1925);
DISPLAY 1.446809 (-2625 1925);
PAINT GREEN (-2625 1925);
DISPLAY INVISIBLE (-2625 1925);
FORCEPROP 1 LAST PATH I104
J 0
(-2952 2050);
DISPLAY 0.872340 (-2952 2050);
PAINT GREEN (-2952 2050);
DISPLAY INVISIBLE (-2952 2050);
FORCEADD TAP..1
(-2950 3150);
FORCEPROP 3 LASTPIN (-3000 3150) SIG_NAME UPI_CPU1_CPU0_P1P1_DP<9>
J 0
(-2990 3160);
DISPLAY 0.659574 (-2990 3160);
PAINT MONO (-2990 3160);
DISPLAY INVISIBLE (-2990 3160);
FORCEPROP 1 LASTPIN (-3000 3150) BN 9
J 0
(-3012 3158);
DISPLAY 0.617021 (-3012 3158);
PAINT GREEN (-3012 3158);
FORCEPROP 2 LAST CDS_LIB mstr_standard
J 0
(-2950 3150);
PAINT MONO (-2950 3150);
DISPLAY INVISIBLE (-2950 3150);
FORCEPROP 1 LAST BODY_TYPE PLUMBING
J 0
(-2950 3200);
DISPLAY 1.446809 (-2950 3200);
PAINT GREEN (-2950 3200);
DISPLAY INVISIBLE (-2950 3200);
FORCEPROP 1 LAST HDL_TAP TRUE
J 0
(-2625 3025);
DISPLAY 1.446809 (-2625 3025);
PAINT GREEN (-2625 3025);
DISPLAY INVISIBLE (-2625 3025);
FORCEPROP 1 LAST PATH I105
J 0
(-2952 3150);
DISPLAY 0.872340 (-2952 3150);
PAINT GREEN (-2952 3150);
DISPLAY INVISIBLE (-2952 3150);
FORCEADD TAP..1
(-2950 2200);
FORCEPROP 3 LASTPIN (-3000 2200) SIG_NAME UPI_CPU1_CPU0_P1P1_DP<11>
J 0
(-2990 2210);
DISPLAY 0.659574 (-2990 2210);
PAINT MONO (-2990 2210);
DISPLAY INVISIBLE (-2990 2210);
FORCEPROP 1 LASTPIN (-3000 2200) BN 11
J 0
(-3012 2208);
DISPLAY 0.617021 (-3012 2208);
PAINT GREEN (-3012 2208);
FORCEPROP 2 LAST CDS_LIB mstr_standard
J 0
(-2950 2200);
PAINT MONO (-2950 2200);
DISPLAY INVISIBLE (-2950 2200);
FORCEPROP 1 LAST BODY_TYPE PLUMBING
J 0
(-2950 2250);
DISPLAY 1.446809 (-2950 2250);
PAINT GREEN (-2950 2250);
DISPLAY INVISIBLE (-2950 2250);
FORCEPROP 1 LAST HDL_TAP TRUE
J 0
(-2625 2075);
DISPLAY 1.446809 (-2625 2075);
PAINT GREEN (-2625 2075);
DISPLAY INVISIBLE (-2625 2075);
FORCEPROP 1 LAST PATH I106
J 0
(-2952 2200);
DISPLAY 0.872340 (-2952 2200);
PAINT GREEN (-2952 2200);
DISPLAY INVISIBLE (-2952 2200);
FORCEADD TAP..1
(-2950 3350);
FORCEPROP 3 LASTPIN (-3000 3350) SIG_NAME UPI_CPU1_CPU0_P1P1_DP<13>
J 0
(-2990 3360);
DISPLAY 0.659574 (-2990 3360);
PAINT MONO (-2990 3360);
DISPLAY INVISIBLE (-2990 3360);
FORCEPROP 1 LASTPIN (-3000 3350) BN 13
J 0
(-3012 3358);
DISPLAY 0.617021 (-3012 3358);
PAINT GREEN (-3012 3358);
FORCEPROP 2 LAST CDS_LIB mstr_standard
J 0
(-2950 3350);
PAINT MONO (-2950 3350);
DISPLAY INVISIBLE (-2950 3350);
FORCEPROP 1 LAST BODY_TYPE PLUMBING
J 0
(-2950 3400);
DISPLAY 1.446809 (-2950 3400);
PAINT GREEN (-2950 3400);
DISPLAY INVISIBLE (-2950 3400);
FORCEPROP 1 LAST HDL_TAP TRUE
J 0
(-2625 3225);
DISPLAY 1.446809 (-2625 3225);
PAINT GREEN (-2625 3225);
DISPLAY INVISIBLE (-2625 3225);
FORCEPROP 1 LAST PATH I107
J 0
(-2952 3350);
DISPLAY 0.872340 (-2952 3350);
PAINT GREEN (-2952 3350);
DISPLAY INVISIBLE (-2952 3350);
FORCEADD TAP..1
(-2950 3400);
FORCEPROP 3 LASTPIN (-3000 3400) SIG_NAME UPI_CPU1_CPU0_P1P1_DP<14>
J 0
(-2990 3410);
DISPLAY 0.659574 (-2990 3410);
PAINT MONO (-2990 3410);
DISPLAY INVISIBLE (-2990 3410);
FORCEPROP 1 LASTPIN (-3000 3400) BN 14
J 0
(-3012 3408);
DISPLAY 0.617021 (-3012 3408);
PAINT GREEN (-3012 3408);
FORCEPROP 2 LAST CDS_LIB mstr_standard
J 0
(-2950 3400);
PAINT MONO (-2950 3400);
DISPLAY INVISIBLE (-2950 3400);
FORCEPROP 1 LAST BODY_TYPE PLUMBING
J 0
(-2950 3450);
DISPLAY 1.446809 (-2950 3450);
PAINT GREEN (-2950 3450);
DISPLAY INVISIBLE (-2950 3450);
FORCEPROP 1 LAST HDL_TAP TRUE
J 0
(-2625 3275);
DISPLAY 1.446809 (-2625 3275);
PAINT GREEN (-2625 3275);
DISPLAY INVISIBLE (-2625 3275);
FORCEPROP 1 LAST PATH I108
J 0
(-2952 3400);
DISPLAY 0.872340 (-2952 3400);
PAINT GREEN (-2952 3400);
DISPLAY INVISIBLE (-2952 3400);
FORCEADD TAP..1
(-2950 3450);
FORCEPROP 3 LASTPIN (-3000 3450) SIG_NAME UPI_CPU1_CPU0_P1P1_DP<15>
J 0
(-2990 3460);
DISPLAY 0.659574 (-2990 3460);
PAINT MONO (-2990 3460);
DISPLAY INVISIBLE (-2990 3460);
FORCEPROP 1 LASTPIN (-3000 3450) BN 15
J 0
(-3012 3458);
DISPLAY 0.617021 (-3012 3458);
PAINT GREEN (-3012 3458);
FORCEPROP 2 LAST CDS_LIB mstr_standard
J 0
(-2950 3450);
PAINT MONO (-2950 3450);
DISPLAY INVISIBLE (-2950 3450);
FORCEPROP 1 LAST BODY_TYPE PLUMBING
J 0
(-2950 3500);
DISPLAY 1.446809 (-2950 3500);
PAINT GREEN (-2950 3500);
DISPLAY INVISIBLE (-2950 3500);
FORCEPROP 1 LAST HDL_TAP TRUE
J 0
(-2625 3325);
DISPLAY 1.446809 (-2625 3325);
PAINT GREEN (-2625 3325);
DISPLAY INVISIBLE (-2625 3325);
FORCEPROP 1 LAST PATH I109
J 0
(-2952 3450);
DISPLAY 0.872340 (-2952 3450);
PAINT GREEN (-2952 3450);
DISPLAY INVISIBLE (-2952 3450);
FORCEADD TAP..1
R 2
(-5725 2000);
FORCEPROP 3 LASTPIN (-5675 2000) SIG_NAME UPI_CPU0_CPU1_P1P1_DN<7>
J 0
(-5665 2010);
DISPLAY 0.659574 (-5665 2010);
PAINT MONO (-5665 2010);
DISPLAY INVISIBLE (-5665 2010);
FORCEPROP 1 LASTPIN (-5675 2000) BN 7
J 2
(-5663 2008);
DISPLAY 0.617021 (-5663 2008);
PAINT GREEN (-5663 2008);
FORCEPROP 2 LAST CDS_LIB mstr_standard
J 0
(-5725 2000);
PAINT MONO (-5725 2000);
DISPLAY INVISIBLE (-5725 2000);
FORCEPROP 1 LAST BODY_TYPE PLUMBING
J 2
(-5725 2050);
DISPLAY 1.446809 (-5725 2050);
PAINT GREEN (-5725 2050);
DISPLAY INVISIBLE (-5725 2050);
FORCEPROP 1 LAST HDL_TAP TRUE
J 2
(-6050 1875);
DISPLAY 1.446809 (-6050 1875);
PAINT GREEN (-6050 1875);
DISPLAY INVISIBLE (-6050 1875);
FORCEPROP 1 LAST PATH I11
J 2
(-5723 2000);
DISPLAY 0.872340 (-5723 2000);
PAINT GREEN (-5723 2000);
DISPLAY INVISIBLE (-5723 2000);
FORCEADD TAP..1
(-2950 2550);
FORCEPROP 3 LASTPIN (-3000 2550) SIG_NAME UPI_CPU1_CPU0_P1P1_DP<18>
J 0
(-2990 2560);
DISPLAY 0.659574 (-2990 2560);
PAINT MONO (-2990 2560);
DISPLAY INVISIBLE (-2990 2560);
FORCEPROP 1 LASTPIN (-3000 2550) BN 18
J 0
(-3012 2558);
DISPLAY 0.617021 (-3012 2558);
PAINT GREEN (-3012 2558);
FORCEPROP 2 LAST CDS_LIB mstr_standard
J 0
(-2950 2550);
PAINT MONO (-2950 2550);
DISPLAY INVISIBLE (-2950 2550);
FORCEPROP 1 LAST BODY_TYPE PLUMBING
J 0
(-2950 2600);
DISPLAY 1.446809 (-2950 2600);
PAINT GREEN (-2950 2600);
DISPLAY INVISIBLE (-2950 2600);
FORCEPROP 1 LAST HDL_TAP TRUE
J 0
(-2625 2425);
DISPLAY 1.446809 (-2625 2425);
PAINT GREEN (-2625 2425);
DISPLAY INVISIBLE (-2625 2425);
FORCEPROP 1 LAST PATH I110
J 0
(-2952 2550);
DISPLAY 0.872340 (-2952 2550);
PAINT GREEN (-2952 2550);
DISPLAY INVISIBLE (-2952 2550);
FORCEADD TAP..1
(-2950 2600);
FORCEPROP 3 LASTPIN (-3000 2600) SIG_NAME UPI_CPU1_CPU0_P1P1_DP<19>
J 0
(-2990 2610);
DISPLAY 0.659574 (-2990 2610);
PAINT MONO (-2990 2610);
DISPLAY INVISIBLE (-2990 2610);
FORCEPROP 1 LASTPIN (-3000 2600) BN 19
J 0
(-3012 2608);
DISPLAY 0.617021 (-3012 2608);
PAINT GREEN (-3012 2608);
FORCEPROP 2 LAST CDS_LIB mstr_standard
J 0
(-2950 2600);
PAINT MONO (-2950 2600);
DISPLAY INVISIBLE (-2950 2600);
FORCEPROP 1 LAST BODY_TYPE PLUMBING
J 0
(-2950 2650);
DISPLAY 1.446809 (-2950 2650);
PAINT GREEN (-2950 2650);
DISPLAY INVISIBLE (-2950 2650);
FORCEPROP 1 LAST HDL_TAP TRUE
J 0
(-2625 2475);
DISPLAY 1.446809 (-2625 2475);
PAINT GREEN (-2625 2475);
DISPLAY INVISIBLE (-2625 2475);
FORCEPROP 1 LAST PATH I111
J 0
(-2952 2600);
DISPLAY 0.872340 (-2952 2600);
PAINT GREEN (-2952 2600);
DISPLAY INVISIBLE (-2952 2600);
FORCEADD TAP..1
(-2625 2700);
FORCEPROP 3 LASTPIN (-2675 2700) SIG_NAME UPI_CPU1_CPU0_P1P1_DN<0>
J 0
(-2665 2710);
DISPLAY 0.659574 (-2665 2710);
PAINT MONO (-2665 2710);
DISPLAY INVISIBLE (-2665 2710);
FORCEPROP 1 LASTPIN (-2675 2700) BN 0
J 0
(-2687 2708);
DISPLAY 0.617021 (-2687 2708);
PAINT GREEN (-2687 2708);
FORCEPROP 2 LAST CDS_LIB mstr_standard
J 0
(-2625 2700);
PAINT MONO (-2625 2700);
DISPLAY INVISIBLE (-2625 2700);
FORCEPROP 1 LAST BODY_TYPE PLUMBING
J 0
(-2625 2750);
DISPLAY 1.446809 (-2625 2750);
PAINT GREEN (-2625 2750);
DISPLAY INVISIBLE (-2625 2750);
FORCEPROP 1 LAST HDL_TAP TRUE
J 0
(-2300 2575);
DISPLAY 1.446809 (-2300 2575);
PAINT GREEN (-2300 2575);
DISPLAY INVISIBLE (-2300 2575);
FORCEPROP 1 LAST PATH I112
J 0
(-2627 2700);
DISPLAY 0.872340 (-2627 2700);
PAINT GREEN (-2627 2700);
DISPLAY INVISIBLE (-2627 2700);
FORCEADD TAP..1
(-2625 2750);
FORCEPROP 3 LASTPIN (-2675 2750) SIG_NAME UPI_CPU1_CPU0_P1P1_DN<1>
J 0
(-2665 2760);
DISPLAY 0.659574 (-2665 2760);
PAINT MONO (-2665 2760);
DISPLAY INVISIBLE (-2665 2760);
FORCEPROP 1 LASTPIN (-2675 2750) BN 1
J 0
(-2687 2758);
DISPLAY 0.617021 (-2687 2758);
PAINT GREEN (-2687 2758);
FORCEPROP 2 LAST CDS_LIB mstr_standard
J 0
(-2625 2750);
PAINT MONO (-2625 2750);
DISPLAY INVISIBLE (-2625 2750);
FORCEPROP 1 LAST BODY_TYPE PLUMBING
J 0
(-2625 2800);
DISPLAY 1.446809 (-2625 2800);
PAINT GREEN (-2625 2800);
DISPLAY INVISIBLE (-2625 2800);
FORCEPROP 1 LAST HDL_TAP TRUE
J 0
(-2300 2625);
DISPLAY 1.446809 (-2300 2625);
PAINT GREEN (-2300 2625);
DISPLAY INVISIBLE (-2300 2625);
FORCEPROP 1 LAST PATH I113
J 0
(-2627 2750);
DISPLAY 0.872340 (-2627 2750);
PAINT GREEN (-2627 2750);
DISPLAY INVISIBLE (-2627 2750);
FORCEADD TAP..1
(-2625 1900);
FORCEPROP 3 LASTPIN (-2675 1900) SIG_NAME UPI_CPU1_CPU0_P1P1_DN<5>
J 0
(-2665 1910);
DISPLAY 0.659574 (-2665 1910);
PAINT MONO (-2665 1910);
DISPLAY INVISIBLE (-2665 1910);
FORCEPROP 1 LASTPIN (-2675 1900) BN 5
J 0
(-2687 1908);
DISPLAY 0.617021 (-2687 1908);
PAINT GREEN (-2687 1908);
FORCEPROP 2 LAST CDS_LIB mstr_standard
J 0
(-2625 1900);
PAINT MONO (-2625 1900);
DISPLAY INVISIBLE (-2625 1900);
FORCEPROP 1 LAST BODY_TYPE PLUMBING
J 0
(-2625 1950);
DISPLAY 1.446809 (-2625 1950);
PAINT GREEN (-2625 1950);
DISPLAY INVISIBLE (-2625 1950);
FORCEPROP 1 LAST HDL_TAP TRUE
J 0
(-2300 1775);
DISPLAY 1.446809 (-2300 1775);
PAINT GREEN (-2300 1775);
DISPLAY INVISIBLE (-2300 1775);
FORCEPROP 1 LAST PATH I114
J 0
(-2627 1900);
DISPLAY 0.872340 (-2627 1900);
PAINT GREEN (-2627 1900);
DISPLAY INVISIBLE (-2627 1900);
FORCEADD TAP..1
(-2625 3000);
FORCEPROP 3 LASTPIN (-2675 3000) SIG_NAME UPI_CPU1_CPU0_P1P1_DN<6>
J 0
(-2665 3010);
DISPLAY 0.659574 (-2665 3010);
PAINT MONO (-2665 3010);
DISPLAY INVISIBLE (-2665 3010);
FORCEPROP 1 LASTPIN (-2675 3000) BN 6
J 0
(-2687 3008);
DISPLAY 0.617021 (-2687 3008);
PAINT GREEN (-2687 3008);
FORCEPROP 2 LAST CDS_LIB mstr_standard
J 0
(-2625 3000);
PAINT MONO (-2625 3000);
DISPLAY INVISIBLE (-2625 3000);
FORCEPROP 1 LAST BODY_TYPE PLUMBING
J 0
(-2625 3050);
DISPLAY 1.446809 (-2625 3050);
PAINT GREEN (-2625 3050);
DISPLAY INVISIBLE (-2625 3050);
FORCEPROP 1 LAST HDL_TAP TRUE
J 0
(-2300 2875);
DISPLAY 1.446809 (-2300 2875);
PAINT GREEN (-2300 2875);
DISPLAY INVISIBLE (-2300 2875);
FORCEPROP 1 LAST PATH I115
J 0
(-2627 3000);
DISPLAY 0.872340 (-2627 3000);
PAINT GREEN (-2627 3000);
DISPLAY INVISIBLE (-2627 3000);
FORCEADD TAP..1
(-2625 3050);
FORCEPROP 3 LASTPIN (-2675 3050) SIG_NAME UPI_CPU1_CPU0_P1P1_DN<7>
J 0
(-2665 3060);
DISPLAY 0.659574 (-2665 3060);
PAINT MONO (-2665 3060);
DISPLAY INVISIBLE (-2665 3060);
FORCEPROP 1 LASTPIN (-2675 3050) BN 7
J 0
(-2687 3058);
DISPLAY 0.617021 (-2687 3058);
PAINT GREEN (-2687 3058);
FORCEPROP 2 LAST CDS_LIB mstr_standard
J 0
(-2625 3050);
PAINT MONO (-2625 3050);
DISPLAY INVISIBLE (-2625 3050);
FORCEPROP 1 LAST BODY_TYPE PLUMBING
J 0
(-2625 3100);
DISPLAY 1.446809 (-2625 3100);
PAINT GREEN (-2625 3100);
DISPLAY INVISIBLE (-2625 3100);
FORCEPROP 1 LAST HDL_TAP TRUE
J 0
(-2300 2925);
DISPLAY 1.446809 (-2300 2925);
PAINT GREEN (-2300 2925);
DISPLAY INVISIBLE (-2300 2925);
FORCEPROP 1 LAST PATH I116
J 0
(-2627 3050);
DISPLAY 0.872340 (-2627 3050);
PAINT GREEN (-2627 3050);
DISPLAY INVISIBLE (-2627 3050);
FORCEADD TAP..1
(-2625 3100);
FORCEPROP 3 LASTPIN (-2675 3100) SIG_NAME UPI_CPU1_CPU0_P1P1_DN<8>
J 0
(-2665 3110);
DISPLAY 0.659574 (-2665 3110);
PAINT MONO (-2665 3110);
DISPLAY INVISIBLE (-2665 3110);
FORCEPROP 1 LASTPIN (-2675 3100) BN 8
J 0
(-2687 3108);
DISPLAY 0.617021 (-2687 3108);
PAINT GREEN (-2687 3108);
FORCEPROP 2 LAST CDS_LIB mstr_standard
J 0
(-2625 3100);
PAINT MONO (-2625 3100);
DISPLAY INVISIBLE (-2625 3100);
FORCEPROP 1 LAST BODY_TYPE PLUMBING
J 0
(-2625 3150);
DISPLAY 1.446809 (-2625 3150);
PAINT GREEN (-2625 3150);
DISPLAY INVISIBLE (-2625 3150);
FORCEPROP 1 LAST HDL_TAP TRUE
J 0
(-2300 2975);
DISPLAY 1.446809 (-2300 2975);
PAINT GREEN (-2300 2975);
DISPLAY INVISIBLE (-2300 2975);
FORCEPROP 1 LAST PATH I117
J 0
(-2627 3100);
DISPLAY 0.872340 (-2627 3100);
PAINT GREEN (-2627 3100);
DISPLAY INVISIBLE (-2627 3100);
FORCEADD TAP..1
(-2625 2100);
FORCEPROP 3 LASTPIN (-2675 2100) SIG_NAME UPI_CPU1_CPU0_P1P1_DN<9>
J 0
(-2665 2110);
DISPLAY 0.659574 (-2665 2110);
PAINT MONO (-2665 2110);
DISPLAY INVISIBLE (-2665 2110);
FORCEPROP 1 LASTPIN (-2675 2100) BN 9
J 0
(-2687 2108);
DISPLAY 0.617021 (-2687 2108);
PAINT GREEN (-2687 2108);
FORCEPROP 2 LAST CDS_LIB mstr_standard
J 0
(-2625 2100);
PAINT MONO (-2625 2100);
DISPLAY INVISIBLE (-2625 2100);
FORCEPROP 1 LAST BODY_TYPE PLUMBING
J 0
(-2625 2150);
DISPLAY 1.446809 (-2625 2150);
PAINT GREEN (-2625 2150);
DISPLAY INVISIBLE (-2625 2150);
FORCEPROP 1 LAST HDL_TAP TRUE
J 0
(-2300 1975);
DISPLAY 1.446809 (-2300 1975);
PAINT GREEN (-2300 1975);
DISPLAY INVISIBLE (-2300 1975);
FORCEPROP 1 LAST PATH I118
J 0
(-2627 2100);
DISPLAY 0.872340 (-2627 2100);
PAINT GREEN (-2627 2100);
DISPLAY INVISIBLE (-2627 2100);
FORCEADD TAP..1
(-2625 3250);
FORCEPROP 3 LASTPIN (-2675 3250) SIG_NAME UPI_CPU1_CPU0_P1P1_DN<11>
J 0
(-2665 3260);
DISPLAY 0.659574 (-2665 3260);
PAINT MONO (-2665 3260);
DISPLAY INVISIBLE (-2665 3260);
FORCEPROP 1 LASTPIN (-2675 3250) BN 11
J 0
(-2687 3258);
DISPLAY 0.617021 (-2687 3258);
PAINT GREEN (-2687 3258);
FORCEPROP 2 LAST CDS_LIB mstr_standard
J 0
(-2625 3250);
PAINT MONO (-2625 3250);
DISPLAY INVISIBLE (-2625 3250);
FORCEPROP 1 LAST BODY_TYPE PLUMBING
J 0
(-2625 3300);
DISPLAY 1.446809 (-2625 3300);
PAINT GREEN (-2625 3300);
DISPLAY INVISIBLE (-2625 3300);
FORCEPROP 1 LAST HDL_TAP TRUE
J 0
(-2300 3125);
DISPLAY 1.446809 (-2300 3125);
PAINT GREEN (-2300 3125);
DISPLAY INVISIBLE (-2300 3125);
FORCEPROP 1 LAST PATH I119
J 0
(-2627 3250);
DISPLAY 0.872340 (-2627 3250);
PAINT GREEN (-2627 3250);
DISPLAY INVISIBLE (-2627 3250);
FORCEADD TAP..1
(-2625 2300);
FORCEPROP 3 LASTPIN (-2675 2300) SIG_NAME UPI_CPU1_CPU0_P1P1_DN<13>
J 0
(-2665 2310);
DISPLAY 0.659574 (-2665 2310);
PAINT MONO (-2665 2310);
DISPLAY INVISIBLE (-2665 2310);
FORCEPROP 1 LASTPIN (-2675 2300) BN 13
J 0
(-2687 2308);
DISPLAY 0.617021 (-2687 2308);
PAINT GREEN (-2687 2308);
FORCEPROP 2 LAST CDS_LIB mstr_standard
J 0
(-2625 2300);
PAINT MONO (-2625 2300);
DISPLAY INVISIBLE (-2625 2300);
FORCEPROP 1 LAST BODY_TYPE PLUMBING
J 0
(-2625 2350);
DISPLAY 1.446809 (-2625 2350);
PAINT GREEN (-2625 2350);
DISPLAY INVISIBLE (-2625 2350);
FORCEPROP 1 LAST HDL_TAP TRUE
J 0
(-2300 2175);
DISPLAY 1.446809 (-2300 2175);
PAINT GREEN (-2300 2175);
DISPLAY INVISIBLE (-2300 2175);
FORCEPROP 1 LAST PATH I120
J 0
(-2627 2300);
DISPLAY 0.872340 (-2627 2300);
PAINT GREEN (-2627 2300);
DISPLAY INVISIBLE (-2627 2300);
FORCEADD TAP..1
(-2625 2350);
FORCEPROP 3 LASTPIN (-2675 2350) SIG_NAME UPI_CPU1_CPU0_P1P1_DN<14>
J 0
(-2665 2360);
DISPLAY 0.659574 (-2665 2360);
PAINT MONO (-2665 2360);
DISPLAY INVISIBLE (-2665 2360);
FORCEPROP 1 LASTPIN (-2675 2350) BN 14
J 0
(-2687 2358);
DISPLAY 0.617021 (-2687 2358);
PAINT GREEN (-2687 2358);
FORCEPROP 2 LAST CDS_LIB mstr_standard
J 0
(-2625 2350);
PAINT MONO (-2625 2350);
DISPLAY INVISIBLE (-2625 2350);
FORCEPROP 1 LAST BODY_TYPE PLUMBING
J 0
(-2625 2400);
DISPLAY 1.446809 (-2625 2400);
PAINT GREEN (-2625 2400);
DISPLAY INVISIBLE (-2625 2400);
FORCEPROP 1 LAST HDL_TAP TRUE
J 0
(-2300 2225);
DISPLAY 1.446809 (-2300 2225);
PAINT GREEN (-2300 2225);
DISPLAY INVISIBLE (-2300 2225);
FORCEPROP 1 LAST PATH I121
J 0
(-2627 2350);
DISPLAY 0.872340 (-2627 2350);
PAINT GREEN (-2627 2350);
DISPLAY INVISIBLE (-2627 2350);
FORCEADD TAP..1
(-2625 2400);
FORCEPROP 3 LASTPIN (-2675 2400) SIG_NAME UPI_CPU1_CPU0_P1P1_DN<15>
J 0
(-2665 2410);
DISPLAY 0.659574 (-2665 2410);
PAINT MONO (-2665 2410);
DISPLAY INVISIBLE (-2665 2410);
FORCEPROP 1 LASTPIN (-2675 2400) BN 15
J 0
(-2687 2408);
DISPLAY 0.617021 (-2687 2408);
PAINT GREEN (-2687 2408);
FORCEPROP 2 LAST CDS_LIB mstr_standard
J 0
(-2625 2400);
PAINT MONO (-2625 2400);
DISPLAY INVISIBLE (-2625 2400);
FORCEPROP 1 LAST BODY_TYPE PLUMBING
J 0
(-2625 2450);
DISPLAY 1.446809 (-2625 2450);
PAINT GREEN (-2625 2450);
DISPLAY INVISIBLE (-2625 2450);
FORCEPROP 1 LAST HDL_TAP TRUE
J 0
(-2300 2275);
DISPLAY 1.446809 (-2300 2275);
PAINT GREEN (-2300 2275);
DISPLAY INVISIBLE (-2300 2275);
FORCEPROP 1 LAST PATH I122
J 0
(-2627 2400);
DISPLAY 0.872340 (-2627 2400);
PAINT GREEN (-2627 2400);
DISPLAY INVISIBLE (-2627 2400);
FORCEADD TAP..1
(-2625 3600);
FORCEPROP 3 LASTPIN (-2675 3600) SIG_NAME UPI_CPU1_CPU0_P1P1_DN<18>
J 0
(-2665 3610);
DISPLAY 0.659574 (-2665 3610);
PAINT MONO (-2665 3610);
DISPLAY INVISIBLE (-2665 3610);
FORCEPROP 1 LASTPIN (-2675 3600) BN 18
J 0
(-2687 3608);
DISPLAY 0.617021 (-2687 3608);
PAINT GREEN (-2687 3608);
FORCEPROP 2 LAST CDS_LIB mstr_standard
J 0
(-2625 3600);
PAINT MONO (-2625 3600);
DISPLAY INVISIBLE (-2625 3600);
FORCEPROP 1 LAST BODY_TYPE PLUMBING
J 0
(-2625 3650);
DISPLAY 1.446809 (-2625 3650);
PAINT GREEN (-2625 3650);
DISPLAY INVISIBLE (-2625 3650);
FORCEPROP 1 LAST HDL_TAP TRUE
J 0
(-2300 3475);
DISPLAY 1.446809 (-2300 3475);
PAINT GREEN (-2300 3475);
DISPLAY INVISIBLE (-2300 3475);
FORCEPROP 1 LAST PATH I123
J 0
(-2627 3600);
DISPLAY 0.872340 (-2627 3600);
PAINT GREEN (-2627 3600);
DISPLAY INVISIBLE (-2627 3600);
FORCEADD TAP..1
(-2625 3650);
FORCEPROP 3 LASTPIN (-2675 3650) SIG_NAME UPI_CPU1_CPU0_P1P1_DN<19>
J 0
(-2665 3660);
DISPLAY 0.659574 (-2665 3660);
PAINT MONO (-2665 3660);
DISPLAY INVISIBLE (-2665 3660);
FORCEPROP 1 LASTPIN (-2675 3650) BN 19
J 0
(-2687 3658);
DISPLAY 0.617021 (-2687 3658);
PAINT GREEN (-2687 3658);
FORCEPROP 2 LAST CDS_LIB mstr_standard
J 2
(-2625 3650);
PAINT MONO (-2625 3650);
DISPLAY INVISIBLE (-2625 3650);
FORCEPROP 1 LAST BODY_TYPE PLUMBING
J 0
(-2625 3700);
DISPLAY 1.446809 (-2625 3700);
PAINT GREEN (-2625 3700);
DISPLAY INVISIBLE (-2625 3700);
FORCEPROP 1 LAST HDL_TAP TRUE
J 0
(-2300 3525);
DISPLAY 1.446809 (-2300 3525);
PAINT GREEN (-2300 3525);
DISPLAY INVISIBLE (-2300 3525);
FORCEPROP 1 LAST PATH I124
J 0
(-2627 3650);
DISPLAY 0.872340 (-2627 3650);
PAINT GREEN (-2627 3650);
DISPLAY INVISIBLE (-2627 3650);
FORCEADD SKX_EXT_B..14
(-4100 2650);
FORCEPROP 1 LAST LOCATION U2D1
J 0
(-4850 3900);
DISPLAY 0.617021 (-4850 3900);
PAINT AQUA (-4850 3900);
FORCEPROP 1 LAST PART_NUMBER TBD
J 0
(-4850 1450);
DISPLAY 0.617021 (-4850 1450);
PAINT BLUE (-4850 1450);
FORCEPROP 1 LAST MATERIAL IC
J 0
(-4850 3850);
DISPLAY 0.617021 (-4850 3850);
PAINT SKYBLUE (-4850 3850);
FORCEPROP 2 LASTPIN (-3300 3650) $PN K21
J 0
(-3290 3660);
DISPLAY 0.617021 (-3290 3660);
PAINT ORANGE (-3290 3660);
FORCEPROP 2 LASTPIN (-3300 3600) $PN G20
J 0
(-3290 3610);
DISPLAY 0.617021 (-3290 3610);
PAINT ORANGE (-3290 3610);
FORCEPROP 2 LASTPIN (-3300 3550) $PN H19
J 0
(-3290 3560);
DISPLAY 0.617021 (-3290 3560);
PAINT ORANGE (-3290 3560);
FORCEPROP 2 LASTPIN (-3300 3500) $PN J18
J 0
(-3290 3510);
DISPLAY 0.617021 (-3290 3510);
PAINT ORANGE (-3290 3510);
FORCEPROP 2 LASTPIN (-3300 3450) $PN L18
J 0
(-3290 3460);
DISPLAY 0.617021 (-3290 3460);
PAINT ORANGE (-3290 3460);
FORCEPROP 2 LASTPIN (-3300 3400) $PN G16
J 0
(-3290 3410);
DISPLAY 0.617021 (-3290 3410);
PAINT ORANGE (-3290 3410);
FORCEPROP 2 LASTPIN (-3300 3350) $PN H15
J 0
(-3290 3360);
DISPLAY 0.617021 (-3290 3360);
PAINT ORANGE (-3290 3360);
FORCEPROP 2 LASTPIN (-3300 3300) $PN E14
J 0
(-3290 3310);
DISPLAY 0.617021 (-3290 3310);
PAINT ORANGE (-3290 3310);
FORCEPROP 2 LASTPIN (-3300 3250) $PN F13
J 0
(-3290 3260);
DISPLAY 0.617021 (-3290 3260);
PAINT ORANGE (-3290 3260);
FORCEPROP 2 LASTPIN (-3300 3200) $PN G12
J 0
(-3290 3210);
DISPLAY 0.617021 (-3290 3210);
PAINT ORANGE (-3290 3210);
FORCEPROP 2 LASTPIN (-3300 3150) $PN H9
J 0
(-3290 3160);
DISPLAY 0.617021 (-3290 3160);
PAINT ORANGE (-3290 3160);
FORCEPROP 2 LASTPIN (-3300 3100) $PN E10
J 0
(-3290 3110);
DISPLAY 0.617021 (-3290 3110);
PAINT ORANGE (-3290 3110);
FORCEPROP 2 LASTPIN (-3300 3050) $PN F9
J 0
(-3290 3060);
DISPLAY 0.617021 (-3290 3060);
PAINT ORANGE (-3290 3060);
FORCEPROP 2 LASTPIN (-3300 3000) $PN J8
J 0
(-3290 3010);
DISPLAY 0.617021 (-3290 3010);
PAINT ORANGE (-3290 3010);
FORCEPROP 2 LASTPIN (-3300 2950) $PN K7
J 0
(-3290 2960);
DISPLAY 0.617021 (-3290 2960);
PAINT ORANGE (-3290 2960);
FORCEPROP 2 LASTPIN (-3300 2900) $PN F7
J 0
(-3290 2910);
DISPLAY 0.617021 (-3290 2910);
PAINT ORANGE (-3290 2910);
FORCEPROP 2 LASTPIN (-3300 2850) $PN H5
J 0
(-3290 2860);
DISPLAY 0.617021 (-3290 2860);
PAINT ORANGE (-3290 2860);
FORCEPROP 2 LASTPIN (-3300 2800) $PN M5
J 0
(-3290 2810);
DISPLAY 0.617021 (-3290 2810);
PAINT ORANGE (-3290 2810);
FORCEPROP 2 LASTPIN (-3300 2750) $PN K3
J 0
(-3290 2760);
DISPLAY 0.617021 (-3290 2760);
PAINT ORANGE (-3290 2760);
FORCEPROP 2 LASTPIN (-3300 2700) $PN P3
J 0
(-3290 2710);
DISPLAY 0.617021 (-3290 2710);
PAINT ORANGE (-3290 2710);
FORCEPROP 2 LASTPIN (-3300 2600) $PN H21
J 0
(-3290 2610);
DISPLAY 0.617021 (-3290 2610);
PAINT ORANGE (-3290 2610);
FORCEPROP 2 LASTPIN (-3300 2550) $PN F21
J 0
(-3290 2560);
DISPLAY 0.617021 (-3290 2560);
PAINT ORANGE (-3290 2560);
FORCEPROP 2 LASTPIN (-3300 2500) $PN J20
J 0
(-3290 2510);
DISPLAY 0.617021 (-3290 2510);
PAINT ORANGE (-3290 2510);
FORCEPROP 2 LASTPIN (-3300 2450) $PN G18
J 0
(-3290 2460);
DISPLAY 0.617021 (-3290 2460);
PAINT ORANGE (-3290 2460);
FORCEPROP 2 LASTPIN (-3300 2400) $PN K19
J 0
(-3290 2410);
DISPLAY 0.617021 (-3290 2410);
PAINT ORANGE (-3290 2410);
FORCEPROP 2 LASTPIN (-3300 2350) $PN H17
J 0
(-3290 2360);
DISPLAY 0.617021 (-3290 2360);
PAINT ORANGE (-3290 2360);
FORCEPROP 2 LASTPIN (-3300 2300) $PN F15
J 0
(-3290 2310);
DISPLAY 0.617021 (-3290 2310);
PAINT ORANGE (-3290 2310);
FORCEPROP 2 LASTPIN (-3300 2250) $PN D15
J 0
(-3290 2260);
DISPLAY 0.617021 (-3290 2260);
PAINT ORANGE (-3290 2260);
FORCEPROP 2 LASTPIN (-3300 2200) $PN G14
J 0
(-3290 2210);
DISPLAY 0.617021 (-3290 2210);
PAINT ORANGE (-3290 2210);
FORCEPROP 2 LASTPIN (-3300 2150) $PN E12
J 0
(-3290 2160);
DISPLAY 0.617021 (-3290 2160);
PAINT ORANGE (-3290 2160);
FORCEPROP 2 LASTPIN (-3300 2100) $PN G10
J 0
(-3290 2110);
DISPLAY 0.617021 (-3290 2110);
PAINT ORANGE (-3290 2110);
FORCEPROP 2 LASTPIN (-3300 2050) $PN F11
J 0
(-3290 2060);
DISPLAY 0.617021 (-3290 2060);
PAINT ORANGE (-3290 2060);
FORCEPROP 2 LASTPIN (-3300 2000) $PN D9
J 0
(-3290 2010);
DISPLAY 0.617021 (-3290 2010);
PAINT ORANGE (-3290 2010);
FORCEPROP 2 LASTPIN (-3300 1950) $PN K9
J 0
(-3290 1960);
DISPLAY 0.617021 (-3290 1960);
PAINT ORANGE (-3290 1960);
FORCEPROP 2 LASTPIN (-3300 1900) $PN H7
J 0
(-3290 1910);
DISPLAY 0.617021 (-3290 1910);
PAINT ORANGE (-3290 1910);
FORCEPROP 2 LASTPIN (-3300 1850) $PN G6
J 0
(-3290 1860);
DISPLAY 0.617021 (-3290 1860);
PAINT ORANGE (-3290 1860);
FORCEPROP 2 LASTPIN (-3300 1800) $PN J6
J 0
(-3290 1810);
DISPLAY 0.617021 (-3290 1810);
PAINT ORANGE (-3290 1810);
FORCEPROP 2 LASTPIN (-3300 1750) $PN K5
J 0
(-3290 1760);
DISPLAY 0.617021 (-3290 1760);
PAINT ORANGE (-3290 1760);
FORCEPROP 2 LASTPIN (-3300 1700) $PN L4
J 0
(-3290 1710);
DISPLAY 0.617021 (-3290 1710);
PAINT ORANGE (-3290 1710);
FORCEPROP 2 LASTPIN (-3300 1650) $PN M3
J 0
(-3290 1660);
DISPLAY 0.617021 (-3290 1660);
PAINT ORANGE (-3290 1660);
FORCEPROP 2 LASTPIN (-4900 3650) $PN AA20
J 2
(-4910 3660);
DISPLAY 0.617021 (-4910 3660);
PAINT ORANGE (-4910 3660);
FORCEPROP 2 LASTPIN (-4900 3600) $PN W20
J 2
(-4910 3610);
DISPLAY 0.617021 (-4910 3610);
PAINT ORANGE (-4910 3610);
FORCEPROP 2 LASTPIN (-4900 3550) $PN Y19
J 2
(-4910 3560);
DISPLAY 0.617021 (-4910 3560);
PAINT ORANGE (-4910 3560);
FORCEPROP 2 LASTPIN (-4900 3500) $PN T21
J 2
(-4910 3510);
DISPLAY 0.617021 (-4910 3510);
PAINT ORANGE (-4910 3510);
FORCEPROP 2 LASTPIN (-4900 3450) $PN T19
J 2
(-4910 3460);
DISPLAY 0.617021 (-4910 3460);
PAINT ORANGE (-4910 3460);
FORCEPROP 2 LASTPIN (-4900 3400) $PN P19
J 2
(-4910 3410);
DISPLAY 0.617021 (-4910 3410);
PAINT ORANGE (-4910 3410);
FORCEPROP 2 LASTPIN (-4900 3350) $PN V17
J 2
(-4910 3360);
DISPLAY 0.617021 (-4910 3360);
PAINT ORANGE (-4910 3360);
FORCEPROP 2 LASTPIN (-4900 3300) $PN W16
J 2
(-4910 3310);
DISPLAY 0.617021 (-4910 3310);
PAINT ORANGE (-4910 3310);
FORCEPROP 2 LASTPIN (-4900 3250) $PN N16
J 2
(-4910 3260);
DISPLAY 0.617021 (-4910 3260);
PAINT ORANGE (-4910 3260);
FORCEPROP 2 LASTPIN (-4900 3200) $PN T15
J 2
(-4910 3210);
DISPLAY 0.617021 (-4910 3210);
PAINT ORANGE (-4910 3210);
FORCEPROP 2 LASTPIN (-4900 3150) $PN P13
J 2
(-4910 3160);
DISPLAY 0.617021 (-4910 3160);
PAINT ORANGE (-4910 3160);
FORCEPROP 2 LASTPIN (-4900 3100) $PN M13
J 2
(-4910 3110);
DISPLAY 0.617021 (-4910 3110);
PAINT ORANGE (-4910 3110);
FORCEPROP 2 LASTPIN (-4900 3050) $PN N12
J 2
(-4910 3060);
DISPLAY 0.617021 (-4910 3060);
PAINT ORANGE (-4910 3060);
FORCEPROP 2 LASTPIN (-4900 3000) $PN T11
J 2
(-4910 3010);
DISPLAY 0.617021 (-4910 3010);
PAINT ORANGE (-4910 3010);
FORCEPROP 2 LASTPIN (-4900 2950) $PN U10
J 2
(-4910 2960);
DISPLAY 0.617021 (-4910 2960);
PAINT ORANGE (-4910 2960);
FORCEPROP 2 LASTPIN (-4900 2900) $PN N10
J 2
(-4910 2910);
DISPLAY 0.617021 (-4910 2910);
PAINT ORANGE (-4910 2910);
FORCEPROP 2 LASTPIN (-4900 2850) $PN R8
J 2
(-4910 2860);
DISPLAY 0.617021 (-4910 2860);
PAINT ORANGE (-4910 2860);
FORCEPROP 2 LASTPIN (-4900 2800) $PN U8
J 2
(-4910 2810);
DISPLAY 0.617021 (-4910 2810);
PAINT ORANGE (-4910 2810);
FORCEPROP 2 LASTPIN (-4900 2750) $PN T7
J 2
(-4910 2760);
DISPLAY 0.617021 (-4910 2760);
PAINT ORANGE (-4910 2760);
FORCEPROP 2 LASTPIN (-4900 2700) $PN R6
J 2
(-4910 2710);
DISPLAY 0.617021 (-4910 2710);
PAINT ORANGE (-4910 2710);
FORCEPROP 2 LASTPIN (-4900 2600) $PN AB19
J 2
(-4910 2610);
DISPLAY 0.617021 (-4910 2610);
PAINT ORANGE (-4910 2610);
FORCEPROP 2 LASTPIN (-4900 2550) $PN Y21
J 2
(-4910 2560);
DISPLAY 0.617021 (-4910 2560);
PAINT ORANGE (-4910 2560);
FORCEPROP 2 LASTPIN (-4900 2500) $PN V19
J 2
(-4910 2510);
DISPLAY 0.617021 (-4910 2510);
PAINT ORANGE (-4910 2510);
FORCEPROP 2 LASTPIN (-4900 2450) $PN P21
J 2
(-4910 2460);
DISPLAY 0.617021 (-4910 2460);
PAINT ORANGE (-4910 2460);
FORCEPROP 2 LASTPIN (-4900 2400) $PN U18
J 2
(-4910 2410);
DISPLAY 0.617021 (-4910 2410);
PAINT ORANGE (-4910 2410);
FORCEPROP 2 LASTPIN (-4900 2350) $PN R20
J 2
(-4910 2360);
DISPLAY 0.617021 (-4910 2360);
PAINT ORANGE (-4910 2360);
FORCEPROP 2 LASTPIN (-4900 2300) $PN W18
J 2
(-4910 2310);
DISPLAY 0.617021 (-4910 2310);
PAINT ORANGE (-4910 2310);
FORCEPROP 2 LASTPIN (-4900 2250) $PN U16
J 2
(-4910 2260);
DISPLAY 0.617021 (-4910 2260);
PAINT ORANGE (-4910 2260);
FORCEPROP 2 LASTPIN (-4900 2200) $PN P17
J 2
(-4910 2210);
DISPLAY 0.617021 (-4910 2210);
PAINT ORANGE (-4910 2210);
FORCEPROP 2 LASTPIN (-4900 2150) $PN R16
J 2
(-4910 2160);
DISPLAY 0.617021 (-4910 2160);
PAINT ORANGE (-4910 2160);
FORCEPROP 2 LASTPIN (-4900 2100) $PN R12
J 2
(-4910 2110);
DISPLAY 0.617021 (-4910 2110);
PAINT ORANGE (-4910 2110);
FORCEPROP 2 LASTPIN (-4900 2050) $PN N14
J 2
(-4910 2060);
DISPLAY 0.617021 (-4910 2060);
PAINT ORANGE (-4910 2060);
FORCEPROP 2 LASTPIN (-4900 2000) $PN L12
J 2
(-4910 2010);
DISPLAY 0.617021 (-4910 2010);
PAINT ORANGE (-4910 2010);
FORCEPROP 2 LASTPIN (-4900 1950) $PN U12
J 2
(-4910 1960);
DISPLAY 0.617021 (-4910 1960);
PAINT ORANGE (-4910 1960);
FORCEPROP 2 LASTPIN (-4900 1900) $PN R10
J 2
(-4910 1910);
DISPLAY 0.617021 (-4910 1910);
PAINT ORANGE (-4910 1910);
FORCEPROP 2 LASTPIN (-4900 1850) $PN P9
J 2
(-4910 1860);
DISPLAY 0.617021 (-4910 1860);
PAINT ORANGE (-4910 1860);
FORCEPROP 2 LASTPIN (-4900 1800) $PN T9
J 2
(-4910 1810);
DISPLAY 0.617021 (-4910 1810);
PAINT ORANGE (-4910 1810);
FORCEPROP 2 LASTPIN (-4900 1750) $PN V7
J 2
(-4910 1760);
DISPLAY 0.617021 (-4910 1760);
PAINT ORANGE (-4910 1760);
FORCEPROP 2 LASTPIN (-4900 1700) $PN P7
J 2
(-4910 1710);
DISPLAY 0.617021 (-4910 1710);
PAINT ORANGE (-4910 1710);
FORCEPROP 2 LASTPIN (-4900 1650) $PN T5
J 2
(-4910 1660);
DISPLAY 0.617021 (-4910 1660);
PAINT ORANGE (-4910 1660);
FORCEPROP 1 LAST PACK_TYPE BGA1
J 0
(-4850 3950);
PAINT SKYBLUE (-4850 3950);
DISPLAY INVISIBLE (-4850 3950);
FORCEPROP 2 LAST SEC_TYPE BGA1
J 0
(-4850 3950);
DISPLAY 1.021277 (-4850 3950);
PAINT ORANGE (-4850 3950);
DISPLAY INVISIBLE (-4850 3950);
FORCEPROP 2 LAST CDS_LIB chpset_lib
J 0
(-4100 2650);
PAINT ORANGE (-4100 2650);
DISPLAY INVISIBLE (-4100 2650);
FORCEPROP 2 LAST SEC 14
J 0
(-4850 3950);
DISPLAY 0.680851 (-4850 3950);
PAINT MONO (-4850 3950);
DISPLAY INVISIBLE (-4850 3950);
FORCEPROP 2 LAST CDS_LOCATION U2D1
J 0
(-4850 3900);
DISPLAY 0.617021 (-4850 3900);
PAINT AQUA (-4850 3900);
DISPLAY INVISIBLE (-4850 3900);
FORCEPROP 1 LAST PATH I125
J 0
(-4100 3850);
PAINT GREEN (-4100 3850);
DISPLAY INVISIBLE (-4100 3850);
FORCEADD TAP..1
R 2
(-5725 2100);
FORCEPROP 3 LASTPIN (-5675 2100) SIG_NAME UPI_CPU0_CPU1_P1P1_DN<9>
J 0
(-5665 2110);
DISPLAY 0.659574 (-5665 2110);
PAINT MONO (-5665 2110);
DISPLAY INVISIBLE (-5665 2110);
FORCEPROP 1 LASTPIN (-5675 2100) BN 9
J 2
(-5663 2108);
DISPLAY 0.617021 (-5663 2108);
PAINT GREEN (-5663 2108);
FORCEPROP 2 LAST CDS_LIB mstr_standard
J 0
(-5725 2100);
PAINT MONO (-5725 2100);
DISPLAY INVISIBLE (-5725 2100);
FORCEPROP 1 LAST BODY_TYPE PLUMBING
J 2
(-5725 2150);
DISPLAY 1.446809 (-5725 2150);
PAINT GREEN (-5725 2150);
DISPLAY INVISIBLE (-5725 2150);
FORCEPROP 1 LAST HDL_TAP TRUE
J 2
(-6050 1975);
DISPLAY 1.446809 (-6050 1975);
PAINT GREEN (-6050 1975);
DISPLAY INVISIBLE (-6050 1975);
FORCEPROP 1 LAST PATH I13
J 2
(-5723 2100);
DISPLAY 0.872340 (-5723 2100);
PAINT GREEN (-5723 2100);
DISPLAY INVISIBLE (-5723 2100);
FORCEADD TAP..1
R 2
(-5725 2150);
FORCEPROP 3 LASTPIN (-5675 2150) SIG_NAME UPI_CPU0_CPU1_P1P1_DN<10>
J 0
(-5665 2160);
DISPLAY 0.659574 (-5665 2160);
PAINT MONO (-5665 2160);
DISPLAY INVISIBLE (-5665 2160);
FORCEPROP 1 LASTPIN (-5675 2150) BN 10
J 2
(-5663 2158);
DISPLAY 0.617021 (-5663 2158);
PAINT GREEN (-5663 2158);
FORCEPROP 2 LAST CDS_LIB mstr_standard
J 0
(-5725 2150);
PAINT MONO (-5725 2150);
DISPLAY INVISIBLE (-5725 2150);
FORCEPROP 1 LAST BODY_TYPE PLUMBING
J 2
(-5725 2200);
DISPLAY 1.446809 (-5725 2200);
PAINT GREEN (-5725 2200);
DISPLAY INVISIBLE (-5725 2200);
FORCEPROP 1 LAST HDL_TAP TRUE
J 2
(-6050 2025);
DISPLAY 1.446809 (-6050 2025);
PAINT GREEN (-6050 2025);
DISPLAY INVISIBLE (-6050 2025);
FORCEPROP 1 LAST PATH I14
J 2
(-5723 2150);
DISPLAY 0.872340 (-5723 2150);
PAINT GREEN (-5723 2150);
DISPLAY INVISIBLE (-5723 2150);
FORCEADD TAP..1
R 2
(-5725 2350);
FORCEPROP 3 LASTPIN (-5675 2350) SIG_NAME UPI_CPU0_CPU1_P1P1_DN<14>
J 0
(-5665 2360);
DISPLAY 0.659574 (-5665 2360);
PAINT MONO (-5665 2360);
DISPLAY INVISIBLE (-5665 2360);
FORCEPROP 1 LASTPIN (-5675 2350) BN 14
J 2
(-5663 2358);
DISPLAY 0.617021 (-5663 2358);
PAINT GREEN (-5663 2358);
FORCEPROP 2 LAST CDS_LIB mstr_standard
J 0
(-5725 2350);
PAINT MONO (-5725 2350);
DISPLAY INVISIBLE (-5725 2350);
FORCEPROP 1 LAST BODY_TYPE PLUMBING
J 2
(-5725 2400);
DISPLAY 1.446809 (-5725 2400);
PAINT GREEN (-5725 2400);
DISPLAY INVISIBLE (-5725 2400);
FORCEPROP 1 LAST HDL_TAP TRUE
J 2
(-6050 2225);
DISPLAY 1.446809 (-6050 2225);
PAINT GREEN (-6050 2225);
DISPLAY INVISIBLE (-6050 2225);
FORCEPROP 1 LAST PATH I18
J 2
(-5723 2350);
DISPLAY 0.872340 (-5723 2350);
PAINT GREEN (-5723 2350);
DISPLAY INVISIBLE (-5723 2350);
FORCEADD OFFPAGE..1
(-6925 3800);
FORCEPROP 2 LAST $XR0 34 
J 0
(-7146 3800);
DISPLAY 0.638298 (-7146 3800);
PAINT MONO (-7146 3800);
FORCEPROP 2 LAST CDS_LIB mstr_standard
J 0
(-6925 3800);
PAINT MONO (-6925 3800);
DISPLAY INVISIBLE (-6925 3800);
FORCEPROP 1 LAST OFFPAGE TRUE
J 0
(-6600 3675);
DISPLAY 1.170213 (-6600 3675);
PAINT GREEN (-6600 3675);
DISPLAY INVISIBLE (-6600 3675);
FORCEPROP 1 LAST COMMENT_BODY TRUE
J 0
(-6800 3700);
DISPLAY 1.170213 (-6800 3700);
PAINT GREEN (-6800 3700);
DISPLAY INVISIBLE (-6800 3700);
FORCEPROP 2 LAST PATH I2
J 0
(-6875 3875);
DISPLAY 1.021277 (-6875 3875);
PAINT ORANGE (-6875 3875);
DISPLAY INVISIBLE (-6875 3875);
FORCEADD TAP..1
R 2
(-5725 2500);
FORCEPROP 3 LASTPIN (-5675 2500) SIG_NAME UPI_CPU0_CPU1_P1P1_DN<17>
J 0
(-5665 2510);
DISPLAY 0.659574 (-5665 2510);
PAINT MONO (-5665 2510);
DISPLAY INVISIBLE (-5665 2510);
FORCEPROP 1 LASTPIN (-5675 2500) BN 17
J 2
(-5663 2508);
DISPLAY 0.617021 (-5663 2508);
PAINT GREEN (-5663 2508);
FORCEPROP 2 LAST CDS_LIB mstr_standard
J 0
(-5725 2500);
PAINT MONO (-5725 2500);
DISPLAY INVISIBLE (-5725 2500);
FORCEPROP 1 LAST BODY_TYPE PLUMBING
J 2
(-5725 2550);
DISPLAY 1.446809 (-5725 2550);
PAINT GREEN (-5725 2550);
DISPLAY INVISIBLE (-5725 2550);
FORCEPROP 1 LAST HDL_TAP TRUE
J 2
(-6050 2375);
DISPLAY 1.446809 (-6050 2375);
PAINT GREEN (-6050 2375);
DISPLAY INVISIBLE (-6050 2375);
FORCEPROP 1 LAST PATH I21
J 2
(-5723 2500);
DISPLAY 0.872340 (-5723 2500);
PAINT GREEN (-5723 2500);
DISPLAY INVISIBLE (-5723 2500);
FORCEADD TAP..1
R 2
(-5725 3600);
FORCEPROP 3 LASTPIN (-5675 3600) SIG_NAME UPI_CPU0_CPU1_P1P1_DN<18>
J 0
(-5665 3610);
DISPLAY 0.659574 (-5665 3610);
PAINT MONO (-5665 3610);
DISPLAY INVISIBLE (-5665 3610);
FORCEPROP 1 LASTPIN (-5675 3600) BN 18
J 2
(-5663 3608);
DISPLAY 0.617021 (-5663 3608);
PAINT GREEN (-5663 3608);
FORCEPROP 2 LAST CDS_LIB mstr_standard
J 0
(-5725 3600);
PAINT MONO (-5725 3600);
DISPLAY INVISIBLE (-5725 3600);
FORCEPROP 1 LAST BODY_TYPE PLUMBING
J 2
(-5725 3650);
DISPLAY 1.446809 (-5725 3650);
PAINT GREEN (-5725 3650);
DISPLAY INVISIBLE (-5725 3650);
FORCEPROP 1 LAST HDL_TAP TRUE
J 2
(-6050 3475);
DISPLAY 1.446809 (-6050 3475);
PAINT GREEN (-6050 3475);
DISPLAY INVISIBLE (-6050 3475);
FORCEPROP 1 LAST PATH I22
J 2
(-5723 3600);
DISPLAY 0.872340 (-5723 3600);
PAINT GREEN (-5723 3600);
DISPLAY INVISIBLE (-5723 3600);
FORCEADD TAP..1
R 2
(-5275 2800);
FORCEPROP 3 LASTPIN (-5225 2800) SIG_NAME UPI_CPU0_CPU1_P1P1_DP<2>
J 0
(-5215 2810);
DISPLAY 0.659574 (-5215 2810);
PAINT MONO (-5215 2810);
DISPLAY INVISIBLE (-5215 2810);
FORCEPROP 1 LASTPIN (-5225 2800) BN 2
J 2
(-5213 2808);
DISPLAY 0.617021 (-5213 2808);
PAINT GREEN (-5213 2808);
FORCEPROP 2 LAST CDS_LIB mstr_standard
J 0
(-5275 2800);
PAINT MONO (-5275 2800);
DISPLAY INVISIBLE (-5275 2800);
FORCEPROP 1 LAST BODY_TYPE PLUMBING
J 2
(-5275 2850);
DISPLAY 1.446809 (-5275 2850);
PAINT GREEN (-5275 2850);
DISPLAY INVISIBLE (-5275 2850);
FORCEPROP 1 LAST HDL_TAP TRUE
J 2
(-5600 2675);
DISPLAY 1.446809 (-5600 2675);
PAINT GREEN (-5600 2675);
DISPLAY INVISIBLE (-5600 2675);
FORCEPROP 1 LAST PATH I26
J 2
(-5273 2800);
DISPLAY 0.872340 (-5273 2800);
PAINT GREEN (-5273 2800);
DISPLAY INVISIBLE (-5273 2800);
FORCEADD TAP..1
R 2
(-5275 2850);
FORCEPROP 3 LASTPIN (-5225 2850) SIG_NAME UPI_CPU0_CPU1_P1P1_DP<3>
J 0
(-5215 2860);
DISPLAY 0.659574 (-5215 2860);
PAINT MONO (-5215 2860);
DISPLAY INVISIBLE (-5215 2860);
FORCEPROP 1 LASTPIN (-5225 2850) BN 3
J 2
(-5213 2858);
DISPLAY 0.617021 (-5213 2858);
PAINT GREEN (-5213 2858);
FORCEPROP 2 LAST CDS_LIB mstr_standard
J 0
(-5275 2850);
PAINT MONO (-5275 2850);
DISPLAY INVISIBLE (-5275 2850);
FORCEPROP 1 LAST BODY_TYPE PLUMBING
J 2
(-5275 2900);
DISPLAY 1.446809 (-5275 2900);
PAINT GREEN (-5275 2900);
DISPLAY INVISIBLE (-5275 2900);
FORCEPROP 1 LAST HDL_TAP TRUE
J 2
(-5600 2725);
DISPLAY 1.446809 (-5600 2725);
PAINT GREEN (-5600 2725);
DISPLAY INVISIBLE (-5600 2725);
FORCEPROP 1 LAST PATH I27
J 2
(-5273 2850);
DISPLAY 0.872340 (-5273 2850);
PAINT GREEN (-5273 2850);
DISPLAY INVISIBLE (-5273 2850);
FORCEADD TAP..1
R 2
(-5275 2900);
FORCEPROP 3 LASTPIN (-5225 2900) SIG_NAME UPI_CPU0_CPU1_P1P1_DP<4>
J 0
(-5215 2910);
DISPLAY 0.659574 (-5215 2910);
PAINT MONO (-5215 2910);
DISPLAY INVISIBLE (-5215 2910);
FORCEPROP 1 LASTPIN (-5225 2900) BN 4
J 2
(-5213 2908);
DISPLAY 0.617021 (-5213 2908);
PAINT GREEN (-5213 2908);
FORCEPROP 2 LAST CDS_LIB mstr_standard
J 0
(-5275 2900);
PAINT MONO (-5275 2900);
DISPLAY INVISIBLE (-5275 2900);
FORCEPROP 1 LAST BODY_TYPE PLUMBING
J 2
(-5275 2950);
DISPLAY 1.446809 (-5275 2950);
PAINT GREEN (-5275 2950);
DISPLAY INVISIBLE (-5275 2950);
FORCEPROP 1 LAST HDL_TAP TRUE
J 2
(-5600 2775);
DISPLAY 1.446809 (-5600 2775);
PAINT GREEN (-5600 2775);
DISPLAY INVISIBLE (-5600 2775);
FORCEPROP 1 LAST PATH I28
J 2
(-5273 2900);
DISPLAY 0.872340 (-5273 2900);
PAINT GREEN (-5273 2900);
DISPLAY INVISIBLE (-5273 2900);
FORCEADD TAP..1
R 2
(-5275 2950);
FORCEPROP 3 LASTPIN (-5225 2950) SIG_NAME UPI_CPU0_CPU1_P1P1_DP<5>
J 0
(-5215 2960);
DISPLAY 0.659574 (-5215 2960);
PAINT MONO (-5215 2960);
DISPLAY INVISIBLE (-5215 2960);
FORCEPROP 1 LASTPIN (-5225 2950) BN 5
J 2
(-5213 2958);
DISPLAY 0.617021 (-5213 2958);
PAINT GREEN (-5213 2958);
FORCEPROP 2 LAST CDS_LIB mstr_standard
J 0
(-5275 2950);
PAINT MONO (-5275 2950);
DISPLAY INVISIBLE (-5275 2950);
FORCEPROP 1 LAST BODY_TYPE PLUMBING
J 2
(-5275 3000);
DISPLAY 1.446809 (-5275 3000);
PAINT GREEN (-5275 3000);
DISPLAY INVISIBLE (-5275 3000);
FORCEPROP 1 LAST HDL_TAP TRUE
J 2
(-5600 2825);
DISPLAY 1.446809 (-5600 2825);
PAINT GREEN (-5600 2825);
DISPLAY INVISIBLE (-5600 2825);
FORCEPROP 1 LAST PATH I29
J 2
(-5273 2950);
DISPLAY 0.872340 (-5273 2950);
PAINT GREEN (-5273 2950);
DISPLAY INVISIBLE (-5273 2950);
FORCEADD TAP..1
R 2
(-5275 3000);
FORCEPROP 3 LASTPIN (-5225 3000) SIG_NAME UPI_CPU0_CPU1_P1P1_DP<6>
J 0
(-5215 3010);
DISPLAY 0.659574 (-5215 3010);
PAINT MONO (-5215 3010);
DISPLAY INVISIBLE (-5215 3010);
FORCEPROP 1 LASTPIN (-5225 3000) BN 6
J 2
(-5213 3008);
DISPLAY 0.617021 (-5213 3008);
PAINT GREEN (-5213 3008);
FORCEPROP 2 LAST CDS_LIB mstr_standard
J 0
(-5275 3000);
PAINT MONO (-5275 3000);
DISPLAY INVISIBLE (-5275 3000);
FORCEPROP 1 LAST BODY_TYPE PLUMBING
J 2
(-5275 3050);
DISPLAY 1.446809 (-5275 3050);
PAINT GREEN (-5275 3050);
DISPLAY INVISIBLE (-5275 3050);
FORCEPROP 1 LAST HDL_TAP TRUE
J 2
(-5600 2875);
DISPLAY 1.446809 (-5600 2875);
PAINT GREEN (-5600 2875);
DISPLAY INVISIBLE (-5600 2875);
FORCEPROP 1 LAST PATH I30
J 2
(-5273 3000);
DISPLAY 0.872340 (-5273 3000);
PAINT GREEN (-5273 3000);
DISPLAY INVISIBLE (-5273 3000);
FORCEADD TAP..1
R 2
(-5275 3050);
FORCEPROP 3 LASTPIN (-5225 3050) SIG_NAME UPI_CPU0_CPU1_P1P1_DP<7>
J 0
(-5215 3060);
DISPLAY 0.659574 (-5215 3060);
PAINT MONO (-5215 3060);
DISPLAY INVISIBLE (-5215 3060);
FORCEPROP 1 LASTPIN (-5225 3050) BN 7
J 2
(-5213 3058);
DISPLAY 0.617021 (-5213 3058);
PAINT GREEN (-5213 3058);
FORCEPROP 2 LAST CDS_LIB mstr_standard
J 0
(-5275 3050);
PAINT MONO (-5275 3050);
DISPLAY INVISIBLE (-5275 3050);
FORCEPROP 1 LAST BODY_TYPE PLUMBING
J 2
(-5275 3100);
DISPLAY 1.446809 (-5275 3100);
PAINT GREEN (-5275 3100);
DISPLAY INVISIBLE (-5275 3100);
FORCEPROP 1 LAST HDL_TAP TRUE
J 2
(-5600 2925);
DISPLAY 1.446809 (-5600 2925);
PAINT GREEN (-5600 2925);
DISPLAY INVISIBLE (-5600 2925);
FORCEPROP 1 LAST PATH I31
J 2
(-5273 3050);
DISPLAY 0.872340 (-5273 3050);
PAINT GREEN (-5273 3050);
DISPLAY INVISIBLE (-5273 3050);
FORCEADD TAP..1
R 2
(-5275 2050);
FORCEPROP 3 LASTPIN (-5225 2050) SIG_NAME UPI_CPU0_CPU1_P1P1_DP<8>
J 0
(-5215 2060);
DISPLAY 0.659574 (-5215 2060);
PAINT MONO (-5215 2060);
DISPLAY INVISIBLE (-5215 2060);
FORCEPROP 1 LASTPIN (-5225 2050) BN 8
J 2
(-5213 2058);
DISPLAY 0.617021 (-5213 2058);
PAINT GREEN (-5213 2058);
FORCEPROP 2 LAST CDS_LIB mstr_standard
J 0
(-5275 2050);
PAINT MONO (-5275 2050);
DISPLAY INVISIBLE (-5275 2050);
FORCEPROP 1 LAST BODY_TYPE PLUMBING
J 2
(-5275 2100);
DISPLAY 1.446809 (-5275 2100);
PAINT GREEN (-5275 2100);
DISPLAY INVISIBLE (-5275 2100);
FORCEPROP 1 LAST HDL_TAP TRUE
J 2
(-5600 1925);
DISPLAY 1.446809 (-5600 1925);
PAINT GREEN (-5600 1925);
DISPLAY INVISIBLE (-5600 1925);
FORCEPROP 1 LAST PATH I32
J 2
(-5273 2050);
DISPLAY 0.872340 (-5273 2050);
PAINT GREEN (-5273 2050);
DISPLAY INVISIBLE (-5273 2050);
FORCEADD TAP..1
R 2
(-5275 3150);
FORCEPROP 3 LASTPIN (-5225 3150) SIG_NAME UPI_CPU0_CPU1_P1P1_DP<9>
J 0
(-5215 3160);
DISPLAY 0.659574 (-5215 3160);
PAINT MONO (-5215 3160);
DISPLAY INVISIBLE (-5215 3160);
FORCEPROP 1 LASTPIN (-5225 3150) BN 9
J 2
(-5213 3158);
DISPLAY 0.617021 (-5213 3158);
PAINT GREEN (-5213 3158);
FORCEPROP 2 LAST CDS_LIB mstr_standard
J 0
(-5275 3150);
PAINT MONO (-5275 3150);
DISPLAY INVISIBLE (-5275 3150);
FORCEPROP 1 LAST BODY_TYPE PLUMBING
J 2
(-5275 3200);
DISPLAY 1.446809 (-5275 3200);
PAINT GREEN (-5275 3200);
DISPLAY INVISIBLE (-5275 3200);
FORCEPROP 1 LAST HDL_TAP TRUE
J 2
(-5600 3025);
DISPLAY 1.446809 (-5600 3025);
PAINT GREEN (-5600 3025);
DISPLAY INVISIBLE (-5600 3025);
FORCEPROP 1 LAST PATH I33
J 2
(-5273 3150);
DISPLAY 0.872340 (-5273 3150);
PAINT GREEN (-5273 3150);
DISPLAY INVISIBLE (-5273 3150);
FORCEADD TAP..1
R 2
(-5275 3200);
FORCEPROP 3 LASTPIN (-5225 3200) SIG_NAME UPI_CPU0_CPU1_P1P1_DP<10>
J 0
(-5215 3210);
DISPLAY 0.659574 (-5215 3210);
PAINT MONO (-5215 3210);
DISPLAY INVISIBLE (-5215 3210);
FORCEPROP 1 LASTPIN (-5225 3200) BN 10
J 2
(-5213 3208);
DISPLAY 0.617021 (-5213 3208);
PAINT GREEN (-5213 3208);
FORCEPROP 2 LAST CDS_LIB mstr_standard
J 0
(-5275 3200);
PAINT MONO (-5275 3200);
DISPLAY INVISIBLE (-5275 3200);
FORCEPROP 1 LAST BODY_TYPE PLUMBING
J 2
(-5275 3250);
DISPLAY 1.446809 (-5275 3250);
PAINT GREEN (-5275 3250);
DISPLAY INVISIBLE (-5275 3250);
FORCEPROP 1 LAST HDL_TAP TRUE
J 2
(-5600 3075);
DISPLAY 1.446809 (-5600 3075);
PAINT GREEN (-5600 3075);
DISPLAY INVISIBLE (-5600 3075);
FORCEPROP 1 LAST PATH I34
J 2
(-5273 3200);
DISPLAY 0.872340 (-5273 3200);
PAINT GREEN (-5273 3200);
DISPLAY INVISIBLE (-5273 3200);
FORCEADD TAP..1
R 2
(-5275 2200);
FORCEPROP 3 LASTPIN (-5225 2200) SIG_NAME UPI_CPU0_CPU1_P1P1_DP<11>
J 0
(-5215 2210);
DISPLAY 0.659574 (-5215 2210);
PAINT MONO (-5215 2210);
DISPLAY INVISIBLE (-5215 2210);
FORCEPROP 1 LASTPIN (-5225 2200) BN 11
J 2
(-5213 2208);
DISPLAY 0.617021 (-5213 2208);
PAINT GREEN (-5213 2208);
FORCEPROP 2 LAST CDS_LIB mstr_standard
J 0
(-5275 2200);
PAINT MONO (-5275 2200);
DISPLAY INVISIBLE (-5275 2200);
FORCEPROP 1 LAST BODY_TYPE PLUMBING
J 2
(-5275 2250);
DISPLAY 1.446809 (-5275 2250);
PAINT GREEN (-5275 2250);
DISPLAY INVISIBLE (-5275 2250);
FORCEPROP 1 LAST HDL_TAP TRUE
J 2
(-5600 2075);
DISPLAY 1.446809 (-5600 2075);
PAINT GREEN (-5600 2075);
DISPLAY INVISIBLE (-5600 2075);
FORCEPROP 1 LAST PATH I35
J 2
(-5273 2200);
DISPLAY 0.872340 (-5273 2200);
PAINT GREEN (-5273 2200);
DISPLAY INVISIBLE (-5273 2200);
FORCEADD TAP..1
R 2
(-5275 2250);
FORCEPROP 3 LASTPIN (-5225 2250) SIG_NAME UPI_CPU0_CPU1_P1P1_DP<12>
J 0
(-5215 2260);
DISPLAY 0.659574 (-5215 2260);
PAINT MONO (-5215 2260);
DISPLAY INVISIBLE (-5215 2260);
FORCEPROP 1 LASTPIN (-5225 2250) BN 12
J 2
(-5213 2258);
DISPLAY 0.617021 (-5213 2258);
PAINT GREEN (-5213 2258);
FORCEPROP 2 LAST CDS_LIB mstr_standard
J 0
(-5275 2250);
PAINT MONO (-5275 2250);
DISPLAY INVISIBLE (-5275 2250);
FORCEPROP 1 LAST BODY_TYPE PLUMBING
J 2
(-5275 2300);
DISPLAY 1.446809 (-5275 2300);
PAINT GREEN (-5275 2300);
DISPLAY INVISIBLE (-5275 2300);
FORCEPROP 1 LAST HDL_TAP TRUE
J 2
(-5600 2125);
DISPLAY 1.446809 (-5600 2125);
PAINT GREEN (-5600 2125);
DISPLAY INVISIBLE (-5600 2125);
FORCEPROP 1 LAST PATH I36
J 2
(-5273 2250);
DISPLAY 0.872340 (-5273 2250);
PAINT GREEN (-5273 2250);
DISPLAY INVISIBLE (-5273 2250);
FORCEADD TAP..1
R 2
(-5275 2300);
FORCEPROP 3 LASTPIN (-5225 2300) SIG_NAME UPI_CPU0_CPU1_P1P1_DP<13>
J 0
(-5215 2310);
DISPLAY 0.659574 (-5215 2310);
PAINT MONO (-5215 2310);
DISPLAY INVISIBLE (-5215 2310);
FORCEPROP 1 LASTPIN (-5225 2300) BN 13
J 2
(-5213 2308);
DISPLAY 0.617021 (-5213 2308);
PAINT GREEN (-5213 2308);
FORCEPROP 2 LAST CDS_LIB mstr_standard
J 0
(-5275 2300);
PAINT MONO (-5275 2300);
DISPLAY INVISIBLE (-5275 2300);
FORCEPROP 1 LAST BODY_TYPE PLUMBING
J 2
(-5275 2350);
DISPLAY 1.446809 (-5275 2350);
PAINT GREEN (-5275 2350);
DISPLAY INVISIBLE (-5275 2350);
FORCEPROP 1 LAST HDL_TAP TRUE
J 2
(-5600 2175);
DISPLAY 1.446809 (-5600 2175);
PAINT GREEN (-5600 2175);
DISPLAY INVISIBLE (-5600 2175);
FORCEPROP 1 LAST PATH I37
J 2
(-5273 2300);
DISPLAY 0.872340 (-5273 2300);
PAINT GREEN (-5273 2300);
DISPLAY INVISIBLE (-5273 2300);
FORCEADD TAP..1
R 2
(-5275 3400);
FORCEPROP 3 LASTPIN (-5225 3400) SIG_NAME UPI_CPU0_CPU1_P1P1_DP<14>
J 0
(-5215 3410);
DISPLAY 0.659574 (-5215 3410);
PAINT MONO (-5215 3410);
DISPLAY INVISIBLE (-5215 3410);
FORCEPROP 1 LASTPIN (-5225 3400) BN 14
J 2
(-5213 3408);
DISPLAY 0.617021 (-5213 3408);
PAINT GREEN (-5213 3408);
FORCEPROP 2 LAST CDS_LIB mstr_standard
J 0
(-5275 3400);
PAINT MONO (-5275 3400);
DISPLAY INVISIBLE (-5275 3400);
FORCEPROP 1 LAST BODY_TYPE PLUMBING
J 2
(-5275 3450);
DISPLAY 1.446809 (-5275 3450);
PAINT GREEN (-5275 3450);
DISPLAY INVISIBLE (-5275 3450);
FORCEPROP 1 LAST HDL_TAP TRUE
J 2
(-5600 3275);
DISPLAY 1.446809 (-5600 3275);
PAINT GREEN (-5600 3275);
DISPLAY INVISIBLE (-5600 3275);
FORCEPROP 1 LAST PATH I38
J 2
(-5273 3400);
DISPLAY 0.872340 (-5273 3400);
PAINT GREEN (-5273 3400);
DISPLAY INVISIBLE (-5273 3400);
FORCEADD TAP..1
R 2
(-5275 3450);
FORCEPROP 3 LASTPIN (-5225 3450) SIG_NAME UPI_CPU0_CPU1_P1P1_DP<15>
J 0
(-5215 3460);
DISPLAY 0.659574 (-5215 3460);
PAINT MONO (-5215 3460);
DISPLAY INVISIBLE (-5215 3460);
FORCEPROP 1 LASTPIN (-5225 3450) BN 15
J 2
(-5213 3458);
DISPLAY 0.617021 (-5213 3458);
PAINT GREEN (-5213 3458);
FORCEPROP 2 LAST CDS_LIB mstr_standard
J 0
(-5275 3450);
PAINT MONO (-5275 3450);
DISPLAY INVISIBLE (-5275 3450);
FORCEPROP 1 LAST BODY_TYPE PLUMBING
J 2
(-5275 3500);
DISPLAY 1.446809 (-5275 3500);
PAINT GREEN (-5275 3500);
DISPLAY INVISIBLE (-5275 3500);
FORCEPROP 1 LAST HDL_TAP TRUE
J 2
(-5600 3325);
DISPLAY 1.446809 (-5600 3325);
PAINT GREEN (-5600 3325);
DISPLAY INVISIBLE (-5600 3325);
FORCEPROP 1 LAST PATH I39
J 2
(-5273 3450);
DISPLAY 0.872340 (-5273 3450);
PAINT GREEN (-5273 3450);
DISPLAY INVISIBLE (-5273 3450);
FORCEADD TAP..1
R 2
(-5275 3500);
FORCEPROP 3 LASTPIN (-5225 3500) SIG_NAME UPI_CPU0_CPU1_P1P1_DP<16>
J 0
(-5215 3510);
DISPLAY 0.659574 (-5215 3510);
PAINT MONO (-5215 3510);
DISPLAY INVISIBLE (-5215 3510);
FORCEPROP 1 LASTPIN (-5225 3500) BN 16
J 2
(-5213 3508);
DISPLAY 0.617021 (-5213 3508);
PAINT GREEN (-5213 3508);
FORCEPROP 2 LAST CDS_LIB mstr_standard
J 0
(-5275 3500);
PAINT MONO (-5275 3500);
DISPLAY INVISIBLE (-5275 3500);
FORCEPROP 1 LAST BODY_TYPE PLUMBING
J 2
(-5275 3550);
DISPLAY 1.446809 (-5275 3550);
PAINT GREEN (-5275 3550);
DISPLAY INVISIBLE (-5275 3550);
FORCEPROP 1 LAST HDL_TAP TRUE
J 2
(-5600 3375);
DISPLAY 1.446809 (-5600 3375);
PAINT GREEN (-5600 3375);
DISPLAY INVISIBLE (-5600 3375);
FORCEPROP 1 LAST PATH I40
J 2
(-5273 3500);
DISPLAY 0.872340 (-5273 3500);
PAINT GREEN (-5273 3500);
DISPLAY INVISIBLE (-5273 3500);
FORCEADD TAP..1
R 2
(-5275 3550);
FORCEPROP 3 LASTPIN (-5225 3550) SIG_NAME UPI_CPU0_CPU1_P1P1_DP<17>
J 0
(-5215 3560);
DISPLAY 0.659574 (-5215 3560);
PAINT MONO (-5215 3560);
DISPLAY INVISIBLE (-5215 3560);
FORCEPROP 1 LASTPIN (-5225 3550) BN 17
J 2
(-5213 3558);
DISPLAY 0.617021 (-5213 3558);
PAINT GREEN (-5213 3558);
FORCEPROP 2 LAST CDS_LIB mstr_standard
J 0
(-5275 3550);
PAINT MONO (-5275 3550);
DISPLAY INVISIBLE (-5275 3550);
FORCEPROP 1 LAST BODY_TYPE PLUMBING
J 2
(-5275 3600);
DISPLAY 1.446809 (-5275 3600);
PAINT GREEN (-5275 3600);
DISPLAY INVISIBLE (-5275 3600);
FORCEPROP 1 LAST HDL_TAP TRUE
J 2
(-5600 3425);
DISPLAY 1.446809 (-5600 3425);
PAINT GREEN (-5600 3425);
DISPLAY INVISIBLE (-5600 3425);
FORCEPROP 1 LAST PATH I41
J 2
(-5273 3550);
DISPLAY 0.872340 (-5273 3550);
PAINT GREEN (-5273 3550);
DISPLAY INVISIBLE (-5273 3550);
FORCEADD TAP..1
R 2
(-5275 2550);
FORCEPROP 3 LASTPIN (-5225 2550) SIG_NAME UPI_CPU0_CPU1_P1P1_DP<18>
J 0
(-5215 2560);
DISPLAY 0.659574 (-5215 2560);
PAINT MONO (-5215 2560);
DISPLAY INVISIBLE (-5215 2560);
FORCEPROP 1 LASTPIN (-5225 2550) BN 18
J 2
(-5213 2558);
DISPLAY 0.617021 (-5213 2558);
PAINT GREEN (-5213 2558);
FORCEPROP 2 LAST CDS_LIB mstr_standard
J 0
(-5275 2550);
PAINT MONO (-5275 2550);
DISPLAY INVISIBLE (-5275 2550);
FORCEPROP 1 LAST BODY_TYPE PLUMBING
J 2
(-5275 2600);
DISPLAY 1.446809 (-5275 2600);
PAINT GREEN (-5275 2600);
DISPLAY INVISIBLE (-5275 2600);
FORCEPROP 1 LAST HDL_TAP TRUE
J 2
(-5600 2425);
DISPLAY 1.446809 (-5600 2425);
PAINT GREEN (-5600 2425);
DISPLAY INVISIBLE (-5600 2425);
FORCEPROP 1 LAST PATH I42
J 2
(-5273 2550);
DISPLAY 0.872340 (-5273 2550);
PAINT GREEN (-5273 2550);
DISPLAY INVISIBLE (-5273 2550);
FORCEADD TAP..1
R 2
(-5275 2600);
FORCEPROP 3 LASTPIN (-5225 2600) SIG_NAME UPI_CPU0_CPU1_P1P1_DP<19>
J 0
(-5215 2610);
DISPLAY 0.659574 (-5215 2610);
PAINT MONO (-5215 2610);
DISPLAY INVISIBLE (-5215 2610);
FORCEPROP 1 LASTPIN (-5225 2600) BN 19
J 2
(-5213 2608);
DISPLAY 0.617021 (-5213 2608);
PAINT GREEN (-5213 2608);
FORCEPROP 2 LAST CDS_LIB mstr_standard
J 0
(-5275 2600);
PAINT MONO (-5275 2600);
DISPLAY INVISIBLE (-5275 2600);
FORCEPROP 1 LAST BODY_TYPE PLUMBING
J 2
(-5275 2650);
DISPLAY 1.446809 (-5275 2650);
PAINT GREEN (-5275 2650);
DISPLAY INVISIBLE (-5275 2650);
FORCEPROP 1 LAST HDL_TAP TRUE
J 2
(-5600 2475);
DISPLAY 1.446809 (-5600 2475);
PAINT GREEN (-5600 2475);
DISPLAY INVISIBLE (-5600 2475);
FORCEPROP 1 LAST PATH I43
J 2
(-5273 2600);
DISPLAY 0.872340 (-5273 2600);
PAINT GREEN (-5273 2600);
DISPLAY INVISIBLE (-5273 2600);
FORCEADD TAP..1
(-2625 1800);
FORCEPROP 3 LASTPIN (-2675 1800) SIG_NAME UPI_CPU1_CPU0_P1P1_DN<3>
J 0
(-2665 1810);
DISPLAY 0.659574 (-2665 1810);
PAINT MONO (-2665 1810);
DISPLAY INVISIBLE (-2665 1810);
FORCEPROP 1 LASTPIN (-2675 1800) BN 3
J 0
(-2687 1808);
DISPLAY 0.617021 (-2687 1808);
PAINT GREEN (-2687 1808);
FORCEPROP 2 LAST CDS_LIB mstr_standard
J 0
(-2625 1800);
PAINT MONO (-2625 1800);
DISPLAY INVISIBLE (-2625 1800);
FORCEPROP 1 LAST BODY_TYPE PLUMBING
J 0
(-2625 1850);
DISPLAY 1.446809 (-2625 1850);
PAINT GREEN (-2625 1850);
DISPLAY INVISIBLE (-2625 1850);
FORCEPROP 1 LAST HDL_TAP TRUE
J 0
(-2300 1675);
DISPLAY 1.446809 (-2300 1675);
PAINT GREEN (-2300 1675);
DISPLAY INVISIBLE (-2300 1675);
FORCEPROP 1 LAST PATH I46
J 0
(-2627 1800);
DISPLAY 0.872340 (-2627 1800);
PAINT GREEN (-2627 1800);
DISPLAY INVISIBLE (-2627 1800);
FORCEADD TAP..1
(-2625 1750);
FORCEPROP 3 LASTPIN (-2675 1750) SIG_NAME UPI_CPU1_CPU0_P1P1_DN<2>
J 0
(-2665 1760);
DISPLAY 0.659574 (-2665 1760);
PAINT MONO (-2665 1760);
DISPLAY INVISIBLE (-2665 1760);
FORCEPROP 1 LASTPIN (-2675 1750) BN 2
J 0
(-2687 1758);
DISPLAY 0.617021 (-2687 1758);
PAINT GREEN (-2687 1758);
FORCEPROP 2 LAST CDS_LIB mstr_standard
J 0
(-2625 1750);
PAINT MONO (-2625 1750);
DISPLAY INVISIBLE (-2625 1750);
FORCEPROP 1 LAST BODY_TYPE PLUMBING
J 0
(-2625 1800);
DISPLAY 1.446809 (-2625 1800);
PAINT GREEN (-2625 1800);
DISPLAY INVISIBLE (-2625 1800);
FORCEPROP 1 LAST HDL_TAP TRUE
J 0
(-2300 1625);
DISPLAY 1.446809 (-2300 1625);
PAINT GREEN (-2300 1625);
DISPLAY INVISIBLE (-2300 1625);
FORCEPROP 1 LAST PATH I47
J 0
(-2627 1750);
DISPLAY 0.872340 (-2627 1750);
PAINT GREEN (-2627 1750);
DISPLAY INVISIBLE (-2627 1750);
FORCEADD TAP..1
(-2625 1850);
FORCEPROP 3 LASTPIN (-2675 1850) SIG_NAME UPI_CPU1_CPU0_P1P1_DN<4>
J 0
(-2665 1860);
DISPLAY 0.659574 (-2665 1860);
PAINT MONO (-2665 1860);
DISPLAY INVISIBLE (-2665 1860);
FORCEPROP 1 LASTPIN (-2675 1850) BN 4
J 0
(-2687 1858);
DISPLAY 0.617021 (-2687 1858);
PAINT GREEN (-2687 1858);
FORCEPROP 2 LAST CDS_LIB mstr_standard
J 0
(-2625 1850);
PAINT MONO (-2625 1850);
DISPLAY INVISIBLE (-2625 1850);
FORCEPROP 1 LAST BODY_TYPE PLUMBING
J 0
(-2625 1900);
DISPLAY 1.446809 (-2625 1900);
PAINT GREEN (-2625 1900);
DISPLAY INVISIBLE (-2625 1900);
FORCEPROP 1 LAST HDL_TAP TRUE
J 0
(-2300 1725);
DISPLAY 1.446809 (-2300 1725);
PAINT GREEN (-2300 1725);
DISPLAY INVISIBLE (-2300 1725);
FORCEPROP 1 LAST PATH I48
J 0
(-2627 1850);
DISPLAY 0.872340 (-2627 1850);
PAINT GREEN (-2627 1850);
DISPLAY INVISIBLE (-2627 1850);
FORCEADD TAP..1
R 2
(-5725 1800);
FORCEPROP 3 LASTPIN (-5675 1800) SIG_NAME UPI_CPU0_CPU1_P1P1_DN<3>
J 0
(-5665 1810);
DISPLAY 0.659574 (-5665 1810);
PAINT MONO (-5665 1810);
DISPLAY INVISIBLE (-5665 1810);
FORCEPROP 1 LASTPIN (-5675 1800) BN 3
J 2
(-5663 1808);
DISPLAY 0.617021 (-5663 1808);
PAINT GREEN (-5663 1808);
FORCEPROP 2 LAST CDS_LIB mstr_standard
J 0
(-5725 1800);
PAINT MONO (-5725 1800);
DISPLAY INVISIBLE (-5725 1800);
FORCEPROP 1 LAST BODY_TYPE PLUMBING
J 2
(-5725 1850);
DISPLAY 1.446809 (-5725 1850);
PAINT GREEN (-5725 1850);
DISPLAY INVISIBLE (-5725 1850);
FORCEPROP 1 LAST HDL_TAP TRUE
J 2
(-6050 1675);
DISPLAY 1.446809 (-6050 1675);
PAINT GREEN (-6050 1675);
DISPLAY INVISIBLE (-6050 1675);
FORCEPROP 1 LAST PATH I5
J 2
(-5723 1800);
DISPLAY 0.872340 (-5723 1800);
PAINT GREEN (-5723 1800);
DISPLAY INVISIBLE (-5723 1800);
FORCEADD TAP..1
(-2625 2150);
FORCEPROP 3 LASTPIN (-2675 2150) SIG_NAME UPI_CPU1_CPU0_P1P1_DN<10>
J 0
(-2665 2160);
DISPLAY 0.659574 (-2665 2160);
PAINT MONO (-2665 2160);
DISPLAY INVISIBLE (-2665 2160);
FORCEPROP 1 LASTPIN (-2675 2150) BN 10
J 0
(-2687 2158);
DISPLAY 0.617021 (-2687 2158);
PAINT GREEN (-2687 2158);
FORCEPROP 2 LAST CDS_LIB mstr_standard
J 0
(-2625 2150);
PAINT MONO (-2625 2150);
DISPLAY INVISIBLE (-2625 2150);
FORCEPROP 1 LAST BODY_TYPE PLUMBING
J 0
(-2625 2200);
DISPLAY 1.446809 (-2625 2200);
PAINT GREEN (-2625 2200);
DISPLAY INVISIBLE (-2625 2200);
FORCEPROP 1 LAST HDL_TAP TRUE
J 0
(-2300 2025);
DISPLAY 1.446809 (-2300 2025);
PAINT GREEN (-2300 2025);
DISPLAY INVISIBLE (-2300 2025);
FORCEPROP 1 LAST PATH I54
J 0
(-2627 2150);
DISPLAY 0.872340 (-2627 2150);
PAINT GREEN (-2627 2150);
DISPLAY INVISIBLE (-2627 2150);
FORCEADD TAP..1
(-2625 2250);
FORCEPROP 3 LASTPIN (-2675 2250) SIG_NAME UPI_CPU1_CPU0_P1P1_DN<12>
J 0
(-2665 2260);
DISPLAY 0.659574 (-2665 2260);
PAINT MONO (-2665 2260);
DISPLAY INVISIBLE (-2665 2260);
FORCEPROP 1 LASTPIN (-2675 2250) BN 12
J 0
(-2687 2258);
DISPLAY 0.617021 (-2687 2258);
PAINT GREEN (-2687 2258);
FORCEPROP 2 LAST CDS_LIB mstr_standard
J 0
(-2625 2250);
PAINT MONO (-2625 2250);
DISPLAY INVISIBLE (-2625 2250);
FORCEPROP 1 LAST BODY_TYPE PLUMBING
J 0
(-2625 2300);
DISPLAY 1.446809 (-2625 2300);
PAINT GREEN (-2625 2300);
DISPLAY INVISIBLE (-2625 2300);
FORCEPROP 1 LAST HDL_TAP TRUE
J 0
(-2300 2125);
DISPLAY 1.446809 (-2300 2125);
PAINT GREEN (-2300 2125);
DISPLAY INVISIBLE (-2300 2125);
FORCEPROP 1 LAST PATH I56
J 0
(-2627 2250);
DISPLAY 0.872340 (-2627 2250);
PAINT GREEN (-2627 2250);
DISPLAY INVISIBLE (-2627 2250);
FORCEADD TAP..1
R 2
(-5725 1750);
FORCEPROP 3 LASTPIN (-5675 1750) SIG_NAME UPI_CPU0_CPU1_P1P1_DN<2>
J 0
(-5665 1760);
DISPLAY 0.659574 (-5665 1760);
PAINT MONO (-5665 1760);
DISPLAY INVISIBLE (-5665 1760);
FORCEPROP 1 LASTPIN (-5675 1750) BN 2
J 2
(-5663 1758);
DISPLAY 0.617021 (-5663 1758);
PAINT GREEN (-5663 1758);
FORCEPROP 2 LAST CDS_LIB mstr_standard
J 0
(-5725 1750);
PAINT MONO (-5725 1750);
DISPLAY INVISIBLE (-5725 1750);
FORCEPROP 1 LAST BODY_TYPE PLUMBING
J 2
(-5725 1800);
DISPLAY 1.446809 (-5725 1800);
PAINT GREEN (-5725 1800);
DISPLAY INVISIBLE (-5725 1800);
FORCEPROP 1 LAST HDL_TAP TRUE
J 2
(-6050 1625);
DISPLAY 1.446809 (-6050 1625);
PAINT GREEN (-6050 1625);
DISPLAY INVISIBLE (-6050 1625);
FORCEPROP 1 LAST PATH I6
J 2
(-5723 1750);
DISPLAY 0.872340 (-5723 1750);
PAINT GREEN (-5723 1750);
DISPLAY INVISIBLE (-5723 1750);
FORCEADD TAP..1
(-2625 2500);
FORCEPROP 3 LASTPIN (-2675 2500) SIG_NAME UPI_CPU1_CPU0_P1P1_DN<17>
J 0
(-2665 2510);
DISPLAY 0.659574 (-2665 2510);
PAINT MONO (-2665 2510);
DISPLAY INVISIBLE (-2665 2510);
FORCEPROP 1 LASTPIN (-2675 2500) BN 17
J 0
(-2687 2508);
DISPLAY 0.617021 (-2687 2508);
PAINT GREEN (-2687 2508);
FORCEPROP 2 LAST CDS_LIB mstr_standard
J 0
(-2625 2500);
PAINT MONO (-2625 2500);
DISPLAY INVISIBLE (-2625 2500);
FORCEPROP 1 LAST BODY_TYPE PLUMBING
J 0
(-2625 2550);
DISPLAY 1.446809 (-2625 2550);
PAINT GREEN (-2625 2550);
DISPLAY INVISIBLE (-2625 2550);
FORCEPROP 1 LAST HDL_TAP TRUE
J 0
(-2300 2375);
DISPLAY 1.446809 (-2300 2375);
PAINT GREEN (-2300 2375);
DISPLAY INVISIBLE (-2300 2375);
FORCEPROP 1 LAST PATH I60
J 0
(-2627 2500);
DISPLAY 0.872340 (-2627 2500);
PAINT GREEN (-2627 2500);
DISPLAY INVISIBLE (-2627 2500);
FORCEADD TAP..1
(-2625 2450);
FORCEPROP 3 LASTPIN (-2675 2450) SIG_NAME UPI_CPU1_CPU0_P1P1_DN<16>
J 0
(-2665 2460);
DISPLAY 0.659574 (-2665 2460);
PAINT MONO (-2665 2460);
DISPLAY INVISIBLE (-2665 2460);
FORCEPROP 1 LASTPIN (-2675 2450) BN 16
J 0
(-2687 2458);
DISPLAY 0.617021 (-2687 2458);
PAINT GREEN (-2687 2458);
FORCEPROP 2 LAST CDS_LIB mstr_standard
J 0
(-2625 2450);
PAINT MONO (-2625 2450);
DISPLAY INVISIBLE (-2625 2450);
FORCEPROP 1 LAST BODY_TYPE PLUMBING
J 0
(-2625 2500);
DISPLAY 1.446809 (-2625 2500);
PAINT GREEN (-2625 2500);
DISPLAY INVISIBLE (-2625 2500);
FORCEPROP 1 LAST HDL_TAP TRUE
J 0
(-2300 2325);
DISPLAY 1.446809 (-2300 2325);
PAINT GREEN (-2300 2325);
DISPLAY INVISIBLE (-2300 2325);
FORCEPROP 1 LAST PATH I61
J 0
(-2627 2450);
DISPLAY 0.872340 (-2627 2450);
PAINT GREEN (-2627 2450);
DISPLAY INVISIBLE (-2627 2450);
FORCEADD TAP..1
(-2950 2800);
FORCEPROP 3 LASTPIN (-3000 2800) SIG_NAME UPI_CPU1_CPU0_P1P1_DP<2>
J 0
(-2990 2810);
DISPLAY 0.659574 (-2990 2810);
PAINT MONO (-2990 2810);
DISPLAY INVISIBLE (-2990 2810);
FORCEPROP 1 LASTPIN (-3000 2800) BN 2
J 0
(-3012 2808);
DISPLAY 0.617021 (-3012 2808);
PAINT GREEN (-3012 2808);
FORCEPROP 2 LAST CDS_LIB mstr_standard
J 0
(-2950 2800);
PAINT MONO (-2950 2800);
DISPLAY INVISIBLE (-2950 2800);
FORCEPROP 1 LAST BODY_TYPE PLUMBING
J 0
(-2950 2850);
DISPLAY 1.446809 (-2950 2850);
PAINT GREEN (-2950 2850);
DISPLAY INVISIBLE (-2950 2850);
FORCEPROP 1 LAST HDL_TAP TRUE
J 0
(-2625 2675);
DISPLAY 1.446809 (-2625 2675);
PAINT GREEN (-2625 2675);
DISPLAY INVISIBLE (-2625 2675);
FORCEPROP 1 LAST PATH I66
J 0
(-2952 2800);
DISPLAY 0.872340 (-2952 2800);
PAINT GREEN (-2952 2800);
DISPLAY INVISIBLE (-2952 2800);
FORCEADD TAP..1
(-2950 2850);
FORCEPROP 3 LASTPIN (-3000 2850) SIG_NAME UPI_CPU1_CPU0_P1P1_DP<3>
J 0
(-2990 2860);
DISPLAY 0.659574 (-2990 2860);
PAINT MONO (-2990 2860);
DISPLAY INVISIBLE (-2990 2860);
FORCEPROP 1 LASTPIN (-3000 2850) BN 3
J 0
(-3012 2858);
DISPLAY 0.617021 (-3012 2858);
PAINT GREEN (-3012 2858);
FORCEPROP 2 LAST CDS_LIB mstr_standard
J 0
(-2950 2850);
PAINT MONO (-2950 2850);
DISPLAY INVISIBLE (-2950 2850);
FORCEPROP 1 LAST BODY_TYPE PLUMBING
J 0
(-2950 2900);
DISPLAY 1.446809 (-2950 2900);
PAINT GREEN (-2950 2900);
DISPLAY INVISIBLE (-2950 2900);
FORCEPROP 1 LAST HDL_TAP TRUE
J 0
(-2625 2725);
DISPLAY 1.446809 (-2625 2725);
PAINT GREEN (-2625 2725);
DISPLAY INVISIBLE (-2625 2725);
FORCEPROP 1 LAST PATH I67
J 0
(-2952 2850);
DISPLAY 0.872340 (-2952 2850);
PAINT GREEN (-2952 2850);
DISPLAY INVISIBLE (-2952 2850);
FORCEADD TAP..1
(-2950 2900);
FORCEPROP 3 LASTPIN (-3000 2900) SIG_NAME UPI_CPU1_CPU0_P1P1_DP<4>
J 0
(-2990 2910);
DISPLAY 0.659574 (-2990 2910);
PAINT MONO (-2990 2910);
DISPLAY INVISIBLE (-2990 2910);
FORCEPROP 1 LASTPIN (-3000 2900) BN 4
J 0
(-3012 2908);
DISPLAY 0.617021 (-3012 2908);
PAINT GREEN (-3012 2908);
FORCEPROP 2 LAST CDS_LIB mstr_standard
J 0
(-2950 2900);
PAINT MONO (-2950 2900);
DISPLAY INVISIBLE (-2950 2900);
FORCEPROP 1 LAST BODY_TYPE PLUMBING
J 0
(-2950 2950);
DISPLAY 1.446809 (-2950 2950);
PAINT GREEN (-2950 2950);
DISPLAY INVISIBLE (-2950 2950);
FORCEPROP 1 LAST HDL_TAP TRUE
J 0
(-2625 2775);
DISPLAY 1.446809 (-2625 2775);
PAINT GREEN (-2625 2775);
DISPLAY INVISIBLE (-2625 2775);
FORCEPROP 1 LAST PATH I69
J 0
(-2952 2900);
DISPLAY 0.872340 (-2952 2900);
PAINT GREEN (-2952 2900);
DISPLAY INVISIBLE (-2952 2900);
FORCEADD TAP..1
(-2950 3200);
FORCEPROP 3 LASTPIN (-3000 3200) SIG_NAME UPI_CPU1_CPU0_P1P1_DP<10>
J 0
(-2990 3210);
DISPLAY 0.659574 (-2990 3210);
PAINT MONO (-2990 3210);
DISPLAY INVISIBLE (-2990 3210);
FORCEPROP 1 LASTPIN (-3000 3200) BN 10
J 0
(-3012 3208);
DISPLAY 0.617021 (-3012 3208);
PAINT GREEN (-3012 3208);
FORCEPROP 2 LAST CDS_LIB mstr_standard
J 0
(-2950 3200);
PAINT MONO (-2950 3200);
DISPLAY INVISIBLE (-2950 3200);
FORCEPROP 1 LAST BODY_TYPE PLUMBING
J 0
(-2950 3250);
DISPLAY 1.446809 (-2950 3250);
PAINT GREEN (-2950 3250);
DISPLAY INVISIBLE (-2950 3250);
FORCEPROP 1 LAST HDL_TAP TRUE
J 0
(-2625 3075);
DISPLAY 1.446809 (-2625 3075);
PAINT GREEN (-2625 3075);
DISPLAY INVISIBLE (-2625 3075);
FORCEPROP 1 LAST PATH I74
J 0
(-2952 3200);
DISPLAY 0.872340 (-2952 3200);
PAINT GREEN (-2952 3200);
DISPLAY INVISIBLE (-2952 3200);
FORCEADD TAP..1
(-2950 3300);
FORCEPROP 3 LASTPIN (-3000 3300) SIG_NAME UPI_CPU1_CPU0_P1P1_DP<12>
J 0
(-2990 3310);
DISPLAY 0.659574 (-2990 3310);
PAINT MONO (-2990 3310);
DISPLAY INVISIBLE (-2990 3310);
FORCEPROP 1 LASTPIN (-3000 3300) BN 12
J 0
(-3012 3308);
DISPLAY 0.617021 (-3012 3308);
PAINT GREEN (-3012 3308);
FORCEPROP 2 LAST CDS_LIB mstr_standard
J 0
(-2950 3300);
PAINT MONO (-2950 3300);
DISPLAY INVISIBLE (-2950 3300);
FORCEPROP 1 LAST BODY_TYPE PLUMBING
J 0
(-2950 3350);
DISPLAY 1.446809 (-2950 3350);
PAINT GREEN (-2950 3350);
DISPLAY INVISIBLE (-2950 3350);
FORCEPROP 1 LAST HDL_TAP TRUE
J 0
(-2625 3175);
DISPLAY 1.446809 (-2625 3175);
PAINT GREEN (-2625 3175);
DISPLAY INVISIBLE (-2625 3175);
FORCEPROP 1 LAST PATH I76
J 0
(-2952 3300);
DISPLAY 0.872340 (-2952 3300);
PAINT GREEN (-2952 3300);
DISPLAY INVISIBLE (-2952 3300);
FORCEADD TAP..1
(-2950 3500);
FORCEPROP 3 LASTPIN (-3000 3500) SIG_NAME UPI_CPU1_CPU0_P1P1_DP<16>
J 0
(-2990 3510);
DISPLAY 0.659574 (-2990 3510);
PAINT MONO (-2990 3510);
DISPLAY INVISIBLE (-2990 3510);
FORCEPROP 1 LASTPIN (-3000 3500) BN 16
J 0
(-3012 3508);
DISPLAY 0.617021 (-3012 3508);
PAINT GREEN (-3012 3508);
FORCEPROP 2 LAST CDS_LIB mstr_standard
J 0
(-2950 3500);
PAINT MONO (-2950 3500);
DISPLAY INVISIBLE (-2950 3500);
FORCEPROP 1 LAST BODY_TYPE PLUMBING
J 0
(-2950 3550);
DISPLAY 1.446809 (-2950 3550);
PAINT GREEN (-2950 3550);
DISPLAY INVISIBLE (-2950 3550);
FORCEPROP 1 LAST HDL_TAP TRUE
J 0
(-2625 3375);
DISPLAY 1.446809 (-2625 3375);
PAINT GREEN (-2625 3375);
DISPLAY INVISIBLE (-2625 3375);
FORCEPROP 1 LAST PATH I80
J 0
(-2952 3500);
DISPLAY 0.872340 (-2952 3500);
PAINT GREEN (-2952 3500);
DISPLAY INVISIBLE (-2952 3500);
FORCEADD TAP..1
(-2950 3550);
FORCEPROP 3 LASTPIN (-3000 3550) SIG_NAME UPI_CPU1_CPU0_P1P1_DP<17>
J 0
(-2990 3560);
DISPLAY 0.659574 (-2990 3560);
PAINT MONO (-2990 3560);
DISPLAY INVISIBLE (-2990 3560);
FORCEPROP 1 LASTPIN (-3000 3550) BN 17
J 0
(-3012 3558);
DISPLAY 0.617021 (-3012 3558);
PAINT GREEN (-3012 3558);
FORCEPROP 2 LAST CDS_LIB mstr_standard
J 0
(-2950 3550);
PAINT MONO (-2950 3550);
DISPLAY INVISIBLE (-2950 3550);
FORCEPROP 1 LAST BODY_TYPE PLUMBING
J 0
(-2950 3600);
DISPLAY 1.446809 (-2950 3600);
PAINT GREEN (-2950 3600);
DISPLAY INVISIBLE (-2950 3600);
FORCEPROP 1 LAST HDL_TAP TRUE
J 0
(-2625 3425);
DISPLAY 1.446809 (-2625 3425);
PAINT GREEN (-2625 3425);
DISPLAY INVISIBLE (-2625 3425);
FORCEPROP 1 LAST PATH I82
J 0
(-2952 3550);
DISPLAY 0.872340 (-2952 3550);
PAINT GREEN (-2952 3550);
DISPLAY INVISIBLE (-2952 3550);
FORCEADD OFFPAGE..2
(-1750 3750);
FORCEPROP 2 LAST $XR0 34 
J 0
(-1561 3750);
DISPLAY 0.638298 (-1561 3750);
PAINT MONO (-1561 3750);
FORCEPROP 2 LAST CDS_LIB mstr_standard
J 0
(-1750 3750);
PAINT MONO (-1750 3750);
DISPLAY INVISIBLE (-1750 3750);
FORCEPROP 1 LAST OFFPAGE TRUE
J 0
(-1425 3625);
DISPLAY 1.170213 (-1425 3625);
PAINT GREEN (-1425 3625);
DISPLAY INVISIBLE (-1425 3625);
FORCEPROP 1 LAST COMMENT_BODY TRUE
J 0
(-1795 3655);
DISPLAY 1.170213 (-1795 3655);
PAINT GREEN (-1795 3655);
DISPLAY INVISIBLE (-1795 3655);
FORCEPROP 2 LAST PATH I84
J 0
(-1575 3825);
DISPLAY 1.021277 (-1575 3825);
PAINT ORANGE (-1575 3825);
DISPLAY INVISIBLE (-1575 3825);
FORCEADD OFFPAGE..2
(-1750 3800);
FORCEPROP 2 LAST $XR0 34 
J 0
(-1561 3800);
DISPLAY 0.638298 (-1561 3800);
PAINT MONO (-1561 3800);
FORCEPROP 2 LAST CDS_LIB mstr_standard
J 0
(-1750 3800);
PAINT MONO (-1750 3800);
DISPLAY INVISIBLE (-1750 3800);
FORCEPROP 1 LAST OFFPAGE TRUE
J 0
(-1425 3675);
DISPLAY 1.170213 (-1425 3675);
PAINT GREEN (-1425 3675);
DISPLAY INVISIBLE (-1425 3675);
FORCEPROP 1 LAST COMMENT_BODY TRUE
J 0
(-1795 3705);
DISPLAY 1.170213 (-1795 3705);
PAINT GREEN (-1795 3705);
DISPLAY INVISIBLE (-1795 3705);
FORCEPROP 2 LAST PATH I85
J 0
(-1575 3875);
DISPLAY 1.021277 (-1575 3875);
PAINT ORANGE (-1575 3875);
DISPLAY INVISIBLE (-1575 3875);
FORCEADD TAP..1
R 2
(-5725 2700);
FORCEPROP 3 LASTPIN (-5675 2700) SIG_NAME UPI_CPU0_CPU1_P1P1_DN<0>
J 0
(-5665 2710);
DISPLAY 0.659574 (-5665 2710);
PAINT MONO (-5665 2710);
DISPLAY INVISIBLE (-5665 2710);
FORCEPROP 1 LASTPIN (-5675 2700) BN 0
J 2
(-5663 2708);
DISPLAY 0.617021 (-5663 2708);
PAINT GREEN (-5663 2708);
FORCEPROP 2 LAST CDS_LIB mstr_standard
J 0
(-5725 2700);
PAINT MONO (-5725 2700);
DISPLAY INVISIBLE (-5725 2700);
FORCEPROP 1 LAST BODY_TYPE PLUMBING
J 2
(-5725 2750);
DISPLAY 1.446809 (-5725 2750);
PAINT GREEN (-5725 2750);
DISPLAY INVISIBLE (-5725 2750);
FORCEPROP 1 LAST HDL_TAP TRUE
J 2
(-6050 2575);
DISPLAY 1.446809 (-6050 2575);
PAINT GREEN (-6050 2575);
DISPLAY INVISIBLE (-6050 2575);
FORCEPROP 1 LAST PATH I86
J 2
(-5723 2700);
DISPLAY 0.872340 (-5723 2700);
PAINT GREEN (-5723 2700);
DISPLAY INVISIBLE (-5723 2700);
FORCEADD TAP..1
R 2
(-5725 1700);
FORCEPROP 3 LASTPIN (-5675 1700) SIG_NAME UPI_CPU0_CPU1_P1P1_DN<1>
J 0
(-5665 1710);
DISPLAY 0.659574 (-5665 1710);
PAINT MONO (-5665 1710);
DISPLAY INVISIBLE (-5665 1710);
FORCEPROP 1 LASTPIN (-5675 1700) BN 1
J 2
(-5663 1708);
DISPLAY 0.617021 (-5663 1708);
PAINT GREEN (-5663 1708);
FORCEPROP 2 LAST CDS_LIB mstr_standard
J 0
(-5725 1700);
PAINT MONO (-5725 1700);
DISPLAY INVISIBLE (-5725 1700);
FORCEPROP 1 LAST BODY_TYPE PLUMBING
J 2
(-5725 1750);
DISPLAY 1.446809 (-5725 1750);
PAINT GREEN (-5725 1750);
DISPLAY INVISIBLE (-5725 1750);
FORCEPROP 1 LAST HDL_TAP TRUE
J 2
(-6050 1575);
DISPLAY 1.446809 (-6050 1575);
PAINT GREEN (-6050 1575);
DISPLAY INVISIBLE (-6050 1575);
FORCEPROP 1 LAST PATH I87
J 2
(-5723 1700);
DISPLAY 0.872340 (-5723 1700);
PAINT GREEN (-5723 1700);
DISPLAY INVISIBLE (-5723 1700);
FORCEADD TAP..1
R 2
(-5275 1650);
FORCEPROP 3 LASTPIN (-5225 1650) SIG_NAME UPI_CPU0_CPU1_P1P1_DP<0>
J 0
(-5215 1660);
DISPLAY 0.659574 (-5215 1660);
PAINT MONO (-5215 1660);
DISPLAY INVISIBLE (-5215 1660);
FORCEPROP 1 LASTPIN (-5225 1650) BN 0
J 2
(-5213 1658);
DISPLAY 0.617021 (-5213 1658);
PAINT GREEN (-5213 1658);
FORCEPROP 2 LAST CDS_LIB mstr_standard
J 0
(-5275 1650);
PAINT MONO (-5275 1650);
DISPLAY INVISIBLE (-5275 1650);
FORCEPROP 1 LAST BODY_TYPE PLUMBING
J 2
(-5275 1700);
DISPLAY 1.446809 (-5275 1700);
PAINT GREEN (-5275 1700);
DISPLAY INVISIBLE (-5275 1700);
FORCEPROP 1 LAST HDL_TAP TRUE
J 2
(-5600 1525);
DISPLAY 1.446809 (-5600 1525);
PAINT GREEN (-5600 1525);
DISPLAY INVISIBLE (-5600 1525);
FORCEPROP 1 LAST PATH I88
J 2
(-5273 1650);
DISPLAY 0.872340 (-5273 1650);
PAINT GREEN (-5273 1650);
DISPLAY INVISIBLE (-5273 1650);
FORCEADD TAP..1
R 2
(-5275 2750);
FORCEPROP 3 LASTPIN (-5225 2750) SIG_NAME UPI_CPU0_CPU1_P1P1_DP<1>
J 0
(-5215 2760);
DISPLAY 0.659574 (-5215 2760);
PAINT MONO (-5215 2760);
DISPLAY INVISIBLE (-5215 2760);
FORCEPROP 1 LASTPIN (-5225 2750) BN 1
J 2
(-5213 2758);
DISPLAY 0.617021 (-5213 2758);
PAINT GREEN (-5213 2758);
FORCEPROP 2 LAST CDS_LIB mstr_standard
J 0
(-5275 2750);
PAINT MONO (-5275 2750);
DISPLAY INVISIBLE (-5275 2750);
FORCEPROP 1 LAST BODY_TYPE PLUMBING
J 2
(-5275 2800);
DISPLAY 1.446809 (-5275 2800);
PAINT GREEN (-5275 2800);
DISPLAY INVISIBLE (-5275 2800);
FORCEPROP 1 LAST HDL_TAP TRUE
J 2
(-5600 2625);
DISPLAY 1.446809 (-5600 2625);
PAINT GREEN (-5600 2625);
DISPLAY INVISIBLE (-5600 2625);
FORCEPROP 1 LAST PATH I89
J 2
(-5273 2750);
DISPLAY 0.872340 (-5273 2750);
PAINT GREEN (-5273 2750);
DISPLAY INVISIBLE (-5273 2750);
FORCEADD TAP..1
R 2
(-5725 1850);
FORCEPROP 3 LASTPIN (-5675 1850) SIG_NAME UPI_CPU0_CPU1_P1P1_DN<4>
J 0
(-5665 1860);
DISPLAY 0.659574 (-5665 1860);
PAINT MONO (-5665 1860);
DISPLAY INVISIBLE (-5665 1860);
FORCEPROP 1 LASTPIN (-5675 1850) BN 4
J 2
(-5663 1858);
DISPLAY 0.617021 (-5663 1858);
PAINT GREEN (-5663 1858);
FORCEPROP 2 LAST CDS_LIB mstr_standard
J 0
(-5725 1850);
PAINT MONO (-5725 1850);
DISPLAY INVISIBLE (-5725 1850);
FORCEPROP 1 LAST BODY_TYPE PLUMBING
J 2
(-5725 1900);
DISPLAY 1.446809 (-5725 1900);
PAINT GREEN (-5725 1900);
DISPLAY INVISIBLE (-5725 1900);
FORCEPROP 1 LAST HDL_TAP TRUE
J 2
(-6050 1725);
DISPLAY 1.446809 (-6050 1725);
PAINT GREEN (-6050 1725);
DISPLAY INVISIBLE (-6050 1725);
FORCEPROP 1 LAST PATH I90
J 2
(-5723 1850);
DISPLAY 0.872340 (-5723 1850);
PAINT GREEN (-5723 1850);
DISPLAY INVISIBLE (-5723 1850);
FORCEADD TAP..1
R 2
(-5725 1950);
FORCEPROP 3 LASTPIN (-5675 1950) SIG_NAME UPI_CPU0_CPU1_P1P1_DN<6>
J 0
(-5665 1960);
DISPLAY 0.659574 (-5665 1960);
PAINT MONO (-5665 1960);
DISPLAY INVISIBLE (-5665 1960);
FORCEPROP 1 LASTPIN (-5675 1950) BN 6
J 2
(-5663 1958);
DISPLAY 0.617021 (-5663 1958);
PAINT GREEN (-5663 1958);
FORCEPROP 2 LAST CDS_LIB mstr_standard
J 0
(-5725 1950);
PAINT MONO (-5725 1950);
DISPLAY INVISIBLE (-5725 1950);
FORCEPROP 1 LAST BODY_TYPE PLUMBING
J 2
(-5725 2000);
DISPLAY 1.446809 (-5725 2000);
PAINT GREEN (-5725 2000);
DISPLAY INVISIBLE (-5725 2000);
FORCEPROP 1 LAST HDL_TAP TRUE
J 2
(-6050 1825);
DISPLAY 1.446809 (-6050 1825);
PAINT GREEN (-6050 1825);
DISPLAY INVISIBLE (-6050 1825);
FORCEPROP 1 LAST PATH I91
J 2
(-5723 1950);
DISPLAY 0.872340 (-5723 1950);
PAINT GREEN (-5723 1950);
DISPLAY INVISIBLE (-5723 1950);
FORCEADD TAP..1
R 2
(-5725 3100);
FORCEPROP 3 LASTPIN (-5675 3100) SIG_NAME UPI_CPU0_CPU1_P1P1_DN<8>
J 0
(-5665 3110);
DISPLAY 0.659574 (-5665 3110);
PAINT MONO (-5665 3110);
DISPLAY INVISIBLE (-5665 3110);
FORCEPROP 1 LASTPIN (-5675 3100) BN 8
J 2
(-5663 3108);
DISPLAY 0.617021 (-5663 3108);
PAINT GREEN (-5663 3108);
FORCEPROP 2 LAST CDS_LIB mstr_standard
J 0
(-5725 3100);
PAINT MONO (-5725 3100);
DISPLAY INVISIBLE (-5725 3100);
FORCEPROP 1 LAST BODY_TYPE PLUMBING
J 2
(-5725 3150);
DISPLAY 1.446809 (-5725 3150);
PAINT GREEN (-5725 3150);
DISPLAY INVISIBLE (-5725 3150);
FORCEPROP 1 LAST HDL_TAP TRUE
J 2
(-6050 2975);
DISPLAY 1.446809 (-6050 2975);
PAINT GREEN (-6050 2975);
DISPLAY INVISIBLE (-6050 2975);
FORCEPROP 1 LAST PATH I92
J 2
(-5723 3100);
DISPLAY 0.872340 (-5723 3100);
PAINT GREEN (-5723 3100);
DISPLAY INVISIBLE (-5723 3100);
FORCEADD TAP..1
R 2
(-5725 3250);
FORCEPROP 3 LASTPIN (-5675 3250) SIG_NAME UPI_CPU0_CPU1_P1P1_DN<11>
J 0
(-5665 3260);
DISPLAY 0.659574 (-5665 3260);
PAINT MONO (-5665 3260);
DISPLAY INVISIBLE (-5665 3260);
FORCEPROP 1 LASTPIN (-5675 3250) BN 11
J 2
(-5663 3258);
DISPLAY 0.617021 (-5663 3258);
PAINT GREEN (-5663 3258);
FORCEPROP 2 LAST CDS_LIB mstr_standard
J 0
(-5725 3250);
PAINT MONO (-5725 3250);
DISPLAY INVISIBLE (-5725 3250);
FORCEPROP 1 LAST BODY_TYPE PLUMBING
J 2
(-5725 3300);
DISPLAY 1.446809 (-5725 3300);
PAINT GREEN (-5725 3300);
DISPLAY INVISIBLE (-5725 3300);
FORCEPROP 1 LAST HDL_TAP TRUE
J 2
(-6050 3125);
DISPLAY 1.446809 (-6050 3125);
PAINT GREEN (-6050 3125);
DISPLAY INVISIBLE (-6050 3125);
FORCEPROP 1 LAST PATH I93
J 2
(-5723 3250);
DISPLAY 0.872340 (-5723 3250);
PAINT GREEN (-5723 3250);
DISPLAY INVISIBLE (-5723 3250);
FORCEADD TAP..1
R 2
(-5725 3300);
FORCEPROP 3 LASTPIN (-5675 3300) SIG_NAME UPI_CPU0_CPU1_P1P1_DN<12>
J 0
(-5665 3310);
DISPLAY 0.659574 (-5665 3310);
PAINT MONO (-5665 3310);
DISPLAY INVISIBLE (-5665 3310);
FORCEPROP 1 LASTPIN (-5675 3300) BN 12
J 2
(-5663 3308);
DISPLAY 0.617021 (-5663 3308);
PAINT GREEN (-5663 3308);
FORCEPROP 2 LAST CDS_LIB mstr_standard
J 0
(-5725 3300);
PAINT MONO (-5725 3300);
DISPLAY INVISIBLE (-5725 3300);
FORCEPROP 1 LAST BODY_TYPE PLUMBING
J 2
(-5725 3350);
DISPLAY 1.446809 (-5725 3350);
PAINT GREEN (-5725 3350);
DISPLAY INVISIBLE (-5725 3350);
FORCEPROP 1 LAST HDL_TAP TRUE
J 2
(-6050 3175);
DISPLAY 1.446809 (-6050 3175);
PAINT GREEN (-6050 3175);
DISPLAY INVISIBLE (-6050 3175);
FORCEPROP 1 LAST PATH I94
J 2
(-5723 3300);
DISPLAY 0.872340 (-5723 3300);
PAINT GREEN (-5723 3300);
DISPLAY INVISIBLE (-5723 3300);
FORCEADD TAP..1
R 2
(-5725 3350);
FORCEPROP 3 LASTPIN (-5675 3350) SIG_NAME UPI_CPU0_CPU1_P1P1_DN<13>
J 0
(-5665 3360);
DISPLAY 0.659574 (-5665 3360);
PAINT MONO (-5665 3360);
DISPLAY INVISIBLE (-5665 3360);
FORCEPROP 1 LASTPIN (-5675 3350) BN 13
J 2
(-5663 3358);
DISPLAY 0.617021 (-5663 3358);
PAINT GREEN (-5663 3358);
FORCEPROP 2 LAST CDS_LIB mstr_standard
J 0
(-5725 3350);
PAINT MONO (-5725 3350);
DISPLAY INVISIBLE (-5725 3350);
FORCEPROP 1 LAST BODY_TYPE PLUMBING
J 2
(-5725 3400);
DISPLAY 1.446809 (-5725 3400);
PAINT GREEN (-5725 3400);
DISPLAY INVISIBLE (-5725 3400);
FORCEPROP 1 LAST HDL_TAP TRUE
J 2
(-6050 3225);
DISPLAY 1.446809 (-6050 3225);
PAINT GREEN (-6050 3225);
DISPLAY INVISIBLE (-6050 3225);
FORCEPROP 1 LAST PATH I95
J 2
(-5723 3350);
DISPLAY 0.872340 (-5723 3350);
PAINT GREEN (-5723 3350);
DISPLAY INVISIBLE (-5723 3350);
FORCEADD TAP..1
R 2
(-5725 2400);
FORCEPROP 3 LASTPIN (-5675 2400) SIG_NAME UPI_CPU0_CPU1_P1P1_DN<15>
J 0
(-5665 2410);
DISPLAY 0.659574 (-5665 2410);
PAINT MONO (-5665 2410);
DISPLAY INVISIBLE (-5665 2410);
FORCEPROP 1 LASTPIN (-5675 2400) BN 15
J 2
(-5663 2408);
DISPLAY 0.617021 (-5663 2408);
PAINT GREEN (-5663 2408);
FORCEPROP 2 LAST CDS_LIB mstr_standard
J 0
(-5725 2400);
PAINT MONO (-5725 2400);
DISPLAY INVISIBLE (-5725 2400);
FORCEPROP 1 LAST BODY_TYPE PLUMBING
J 2
(-5725 2450);
DISPLAY 1.446809 (-5725 2450);
PAINT GREEN (-5725 2450);
DISPLAY INVISIBLE (-5725 2450);
FORCEPROP 1 LAST HDL_TAP TRUE
J 2
(-6050 2275);
DISPLAY 1.446809 (-6050 2275);
PAINT GREEN (-6050 2275);
DISPLAY INVISIBLE (-6050 2275);
FORCEPROP 1 LAST PATH I96
J 2
(-5723 2400);
DISPLAY 0.872340 (-5723 2400);
PAINT GREEN (-5723 2400);
DISPLAY INVISIBLE (-5723 2400);
FORCEADD TAP..1
R 2
(-5725 2450);
FORCEPROP 3 LASTPIN (-5675 2450) SIG_NAME UPI_CPU0_CPU1_P1P1_DN<16>
J 0
(-5665 2460);
DISPLAY 0.659574 (-5665 2460);
PAINT MONO (-5665 2460);
DISPLAY INVISIBLE (-5665 2460);
FORCEPROP 1 LASTPIN (-5675 2450) BN 16
J 2
(-5663 2458);
DISPLAY 0.617021 (-5663 2458);
PAINT GREEN (-5663 2458);
FORCEPROP 2 LAST CDS_LIB mstr_standard
J 0
(-5725 2450);
PAINT MONO (-5725 2450);
DISPLAY INVISIBLE (-5725 2450);
FORCEPROP 1 LAST BODY_TYPE PLUMBING
J 2
(-5725 2500);
DISPLAY 1.446809 (-5725 2500);
PAINT GREEN (-5725 2500);
DISPLAY INVISIBLE (-5725 2500);
FORCEPROP 1 LAST HDL_TAP TRUE
J 2
(-6050 2325);
DISPLAY 1.446809 (-6050 2325);
PAINT GREEN (-6050 2325);
DISPLAY INVISIBLE (-6050 2325);
FORCEPROP 1 LAST PATH I97
J 2
(-5723 2450);
DISPLAY 0.872340 (-5723 2450);
PAINT GREEN (-5723 2450);
DISPLAY INVISIBLE (-5723 2450);
FORCEADD TAP..1
R 2
(-5725 3650);
FORCEPROP 3 LASTPIN (-5675 3650) SIG_NAME UPI_CPU0_CPU1_P1P1_DN<19>
J 0
(-5665 3660);
DISPLAY 0.659574 (-5665 3660);
PAINT MONO (-5665 3660);
DISPLAY INVISIBLE (-5665 3660);
FORCEPROP 1 LASTPIN (-5675 3650) BN 19
J 2
(-5663 3658);
DISPLAY 0.617021 (-5663 3658);
PAINT GREEN (-5663 3658);
FORCEPROP 2 LAST CDS_LIB mstr_standard
J 0
(-5725 3650);
PAINT ORANGE (-5725 3650);
DISPLAY INVISIBLE (-5725 3650);
FORCEPROP 1 LAST BODY_TYPE PLUMBING
J 2
(-5725 3700);
DISPLAY 1.446809 (-5725 3700);
PAINT GREEN (-5725 3700);
DISPLAY INVISIBLE (-5725 3700);
FORCEPROP 1 LAST HDL_TAP TRUE
J 2
(-6050 3525);
DISPLAY 1.446809 (-6050 3525);
PAINT GREEN (-6050 3525);
DISPLAY INVISIBLE (-6050 3525);
FORCEPROP 1 LAST PATH I98
J 2
(-5723 3650);
DISPLAY 0.872340 (-5723 3650);
PAINT GREEN (-5723 3650);
DISPLAY INVISIBLE (-5723 3650);
FORCEADD TAP..1
(-2950 1650);
FORCEPROP 3 LASTPIN (-3000 1650) SIG_NAME UPI_CPU1_CPU0_P1P1_DP<0>
J 0
(-2990 1660);
DISPLAY 0.659574 (-2990 1660);
PAINT MONO (-2990 1660);
DISPLAY INVISIBLE (-2990 1660);
FORCEPROP 1 LASTPIN (-3000 1650) BN 0
J 0
(-3012 1658);
DISPLAY 0.617021 (-3012 1658);
PAINT GREEN (-3012 1658);
FORCEPROP 2 LAST CDS_LIB mstr_standard
J 0
(-2950 1650);
PAINT MONO (-2950 1650);
DISPLAY INVISIBLE (-2950 1650);
FORCEPROP 1 LAST BODY_TYPE PLUMBING
J 0
(-2950 1700);
DISPLAY 1.446809 (-2950 1700);
PAINT GREEN (-2950 1700);
DISPLAY INVISIBLE (-2950 1700);
FORCEPROP 1 LAST HDL_TAP TRUE
J 0
(-2625 1525);
DISPLAY 1.446809 (-2625 1525);
PAINT GREEN (-2625 1525);
DISPLAY INVISIBLE (-2625 1525);
FORCEPROP 1 LAST PATH I99
J 0
(-2952 1650);
DISPLAY 0.872340 (-2952 1650);
PAINT GREEN (-2952 1650);
DISPLAY INVISIBLE (-2952 1650);
FORCEADD DESIGN_NOTE..1
(-4675 1350);
FORCEPROP 0 LAST L1 CPU SYMBOLS 1-30 ARE PRELIMINARY AND SUBJECT TO CHANGE
J 0
(-4875 1225);
DISPLAY 1.021277 (-4875 1225);
PAINT ORANGE (-4875 1225);
FORCEPROP 2 LAST CDS_LIB mstr_symbols
J 0
(-4675 1350);
PAINT ORANGE (-4675 1350);
DISPLAY INVISIBLE (-4675 1350);
FORCEPROP 1 LAST COMMENT_BODY TRUE
J 0
(-4650 1450);
DISPLAY 0.978723 (-4650 1450);
PAINT ORANGE (-4650 1450);
DISPLAY INVISIBLE (-4650 1450);
FORCEADD PRELIM..10
(-4090 2640);
PAINT GRAY (-4090 2640);
FORCEPROP 2 LAST CDS_LIB mstr_misc
J 0
(-4090 2640);
PAINT ORANGE (-4090 2640);
DISPLAY INVISIBLE (-4090 2640);
FORCEPROP 1 LAST COMMENT_BODY TRUE
J 0
(-4090 2640);
PAINT ORANGE (-4090 2640);
DISPLAY INVISIBLE (-4090 2640);
FORCEADD INTEL_CORP_BPAGE..1
(0 0);
FORCEPROP 1 LAST CDS_CON_LAST_MODIFIED Tue Dec 01 11:51:37 2015
J 0
(-1425 325);
DISPLAY 1.340426 (-1425 325);
PAINT GREEN (-1425 325);
DISPLAY INVISIBLE (-1425 325);
FORCEPROP 1 LAST CUSTOM_TXT_CDS <CURRENT_DESIGN_SHEET> OF <TOTAL_DESIGN_SHEETS>
J 0
(-500 25);
PAINT GREEN (-500 25);
FORCEPROP 1 LAST CUSTOM_TXT_CDS <CON_LAST_MODIFIED>
J 0
(-1925 350);
PAINT GREEN (-1925 350);
FORCEPROP 2 LAST CUSTOM_TXT_CDS <XR_PAGE_TITLE>
J 0
(-7890 5250);
DISPLAY 0.638298 (-7890 5250);
PAINT PINK (-7890 5250);
DISPLAY INVISIBLE (-7890 5250);
FORCEPROP 1 LAST SCH_ADDRESS3 Santa Clara, CA 95052-8119
J 0
(-3975 25);
DISPLAY 0.617021 (-3975 25);
PAINT GREEN (-3975 25);
FORCEPROP 1 LAST SCH_ADDRESS2 P.O. BOX 58119
J 0
(-3975 75);
DISPLAY 0.617021 (-3975 75);
PAINT GREEN (-3975 75);
FORCEPROP 1 LAST SCH_ADDRESS1 2200 Mission College Blvd.
J 0
(-3975 125);
DISPLAY 0.617021 (-3975 125);
PAINT GREEN (-3975 125);
FORCEPROP 1 LAST SCH_TITLE SKYLAKE - SKT1 - 14 OF 21
J 0
(-7950 50);
DISPLAY 1.212766 (-7950 50);
PAINT GREEN (-7950 50);
FORCEPROP 1 LAST SCH_NUMBER H4694802
J 0
(-1300 150);
DISPLAY 1.212766 (-1300 150);
PAINT YELLOW (-1300 150);
FORCEPROP 1 LAST SCH_DEPT BESD
J 1
(-4450 100);
DISPLAY 1.212766 (-4450 100);
PAINT YELLOW (-4450 100);
FORCEPROP 1 LAST SCH_REV 2.420
J 0
(-250 150);
DISPLAY 0.978723 (-250 150);
PAINT YELLOW (-250 150);
FORCEPROP 2 LAST CDS_LIB mstr_symbols
J 0
(0 0);
PAINT ORANGE (0 0);
DISPLAY INVISIBLE (0 0);
FORCEPROP 2 LAST PAGE_BORDER TRUE
J 0
(-7890 5250);
DISPLAY 0.851064 (-7890 5250);
PAINT PINK (-7890 5250);
DISPLAY INVISIBLE (-7890 5250);
FORCEPROP 1 LAST COMMENT_BODY TRUE
J 0
(12 12);
DISPLAY 0.638298 (12 12);
PAINT GREEN (12 12);
DISPLAY INVISIBLE (12 12);
FORCEPROP 2 LAST CDS_XR_PAGE_TITLE CR-68 : @BASEBOARD_FAB2_LIB.BASEBOARD_FAB2(SCH_1):PAGE68
J 0
(-7890 5250);
DISPLAY 0.638298 (-7890 5250);
PAINT PINK (-7890 5250);
DISPLAY INVISIBLE (-7890 5250);
WIRE 17 -1 (-2900 2825)(-2900 2625);
WIRE 17 -1 (-2900 2875)(-2900 2825);
WIRE 17 -1 (-2900 2625)(-2900 2575);
WIRE 17 -1 (-2900 2575)(-2900 2225);
WIRE 17 -1 (-2900 2925)(-2900 2875);
WIRE 17 -1 (-2900 2975)(-2900 2925);
WIRE 17 -1 (-2900 2225)(-2900 2075);
WIRE 17 -1 (-2900 2075)(-2900 2025);
WIRE 17 -1 (-2900 3175)(-2900 2975);
WIRE 17 -1 (-2900 3225)(-2900 3175);
WIRE 17 -1 (-2900 2025)(-2900 1975);
WIRE 17 -1 (-2900 1975)(-2900 1725);
WIRE 17 -1 (-2900 3325)(-2900 3225);
WIRE 17 -1 (-2900 3375)(-2900 3325);
WIRE 17 -1 (-2900 1725)(-2900 1675);
WIRE 17 -1 (-2900 3375)(-2900 3425);
WIRE 17 -1 (-2900 3425)(-2900 3475);
WIRE 17 -1 (-2900 3475)(-2900 3525);
WIRE 17 -1 (-2900 3575)(-2900 3525);
WIRE 17 -1 (-2900 3575)(-2900 3800);
WIRE 17 -1 (-2900 3800)(-1800 3800);
FORCEPROP 2 LAST SIG_NAME UPI_CPU1_CPU0_P1P1_DP<19..0>
J 0
(-2485 3810);
DISPLAY 0.617021 (-2485 3810);
PAINT ORANGE (-2485 3810);
WIRE 17 -1 (-2575 2725)(-2575 2525);
WIRE 17 -1 (-2575 2775)(-2575 2725);
WIRE 17 -1 (-2575 2525)(-2575 2475);
WIRE 17 -1 (-2575 2475)(-2575 2425);
WIRE 17 -1 (-2575 3025)(-2575 2775);
WIRE 17 -1 (-2575 3075)(-2575 3025);
WIRE 17 -1 (-2575 2425)(-2575 2375);
WIRE 17 -1 (-2575 2375)(-2575 2325);
WIRE 17 -1 (-2575 3125)(-2575 3075);
WIRE 17 -1 (-2575 3275)(-2575 3125);
WIRE 17 -1 (-2575 2325)(-2575 2275);
WIRE 17 -1 (-2575 2275)(-2575 2175);
WIRE 17 -1 (-2575 3625)(-2575 3275);
WIRE 17 -1 (-2575 3675)(-2575 3625);
WIRE 17 -1 (-2575 2175)(-2575 2125);
WIRE 17 -1 (-2575 2125)(-2575 1925);
WIRE 17 -1 (-2575 3750)(-2575 3675);
WIRE 17 -1 (-2575 3750)(-1800 3750);
FORCEPROP 2 LAST SIG_NAME UPI_CPU1_CPU0_P1P1_DN<19..0>
J 0
(-2485 3760);
DISPLAY 0.617021 (-2485 3760);
PAINT ORANGE (-2485 3760);
WIRE 17 -1 (-2575 1875)(-2575 1925);
WIRE 17 -1 (-2575 1875)(-2575 1825);
WIRE 17 -1 (-2575 1825)(-2575 1775);
WIRE 17 -1 (-5325 2775)(-5325 2625);
WIRE 17 -1 (-5325 2825)(-5325 2775);
WIRE 17 -1 (-5325 2625)(-5325 2575);
WIRE 17 -1 (-5325 2325)(-5325 2575);
WIRE 17 -1 (-5325 2825)(-5325 2875);
WIRE 17 -1 (-5325 2925)(-5325 2875);
WIRE 17 -1 (-5325 2275)(-5325 2325);
WIRE 17 -1 (-5325 2225)(-5325 2275);
WIRE 17 -1 (-5325 2975)(-5325 2925);
WIRE 17 -1 (-5325 3025)(-5325 2975);
WIRE 17 -1 (-5325 2075)(-5325 2225);
WIRE 17 -1 (-5325 2075)(-5325 1675);
WIRE 17 -1 (-5325 3075)(-5325 3025);
WIRE 17 -1 (-5325 3175)(-5325 3075);
WIRE 17 -1 (-5325 3225)(-5325 3175);
WIRE 17 -1 (-5325 3425)(-5325 3225);
WIRE 17 -1 (-5325 3475)(-5325 3425);
WIRE 17 -1 (-5325 3525)(-5325 3475);
WIRE 17 -1 (-5325 3575)(-5325 3525);
WIRE 17 -1 (-5325 3800)(-5325 3575);
WIRE 17 -1 (-6875 3800)(-5325 3800);
FORCEPROP 2 LAST SIG_NAME UPI_CPU0_CPU1_P1P1_DP<19..0>
J 0
(-6825 3810);
DISPLAY 0.617021 (-6825 3810);
PAINT ORANGE (-6825 3810);
WIRE 17 -1 (-5775 2525)(-5775 2725);
WIRE 17 -1 (-5775 2475)(-5775 2525);
WIRE 17 -1 (-5775 2725)(-5775 3125);
WIRE 17 -1 (-5775 3125)(-5775 3275);
WIRE 17 -1 (-5775 2425)(-5775 2475);
WIRE 17 -1 (-5775 2375)(-5775 2425);
WIRE 17 -1 (-5775 3275)(-5775 3325);
WIRE 17 -1 (-5775 3325)(-5775 3375);
WIRE 17 -1 (-5775 2175)(-5775 2375);
WIRE 17 -1 (-5775 2125)(-5775 2175);
WIRE 17 -1 (-5775 3375)(-5775 3625);
WIRE 17 -1 (-5775 3625)(-5775 3675);
WIRE 17 -1 (-5775 2025)(-5775 2125);
WIRE 17 -1 (-5775 1975)(-5775 2025);
WIRE 17 -1 (-5775 3675)(-5775 3700);
WIRE 17 -1 (-6875 3700)(-5775 3700);
FORCEPROP 2 LAST SIG_NAME UPI_CPU0_CPU1_P1P1_DN<19..0>
J 0
(-6825 3710);
DISPLAY 0.617021 (-6825 3710);
PAINT ORANGE (-6825 3710);
WIRE 17 -1 (-5775 1925)(-5775 1975);
WIRE 17 -1 (-5775 1875)(-5775 1925);
WIRE 17 -1 (-5775 1825)(-5775 1875);
WIRE 17 -1 (-5775 1775)(-5775 1825);
WIRE 17 -1 (-5775 1725)(-5775 1775);
WIRE 16 -1 (-5225 1650)(-4900 1650);
WIRE 16 -1 (-5675 1700)(-4900 1700);
WIRE 16 -1 (-5675 1750)(-4900 1750);
WIRE 16 -1 (-5675 1800)(-4900 1800);
WIRE 16 -1 (-5675 1850)(-4900 1850);
WIRE 16 -1 (-5675 1900)(-4900 1900);
WIRE 16 -1 (-5675 1950)(-4900 1950);
WIRE 16 -1 (-5675 2000)(-4900 2000);
WIRE 16 -1 (-5675 2700)(-4900 2700);
WIRE 16 -1 (-5225 2750)(-4900 2750);
WIRE 16 -1 (-5225 2800)(-4900 2800);
WIRE 16 -1 (-5225 2850)(-4900 2850);
WIRE 16 -1 (-5225 2900)(-4900 2900);
WIRE 16 -1 (-5225 2950)(-4900 2950);
WIRE 16 -1 (-5225 3000)(-4900 3000);
WIRE 16 -1 (-5225 3050)(-4900 3050);
WIRE 16 -1 (-5675 3100)(-4900 3100);
WIRE 16 -1 (-5225 3150)(-4900 3150);
WIRE 16 -1 (-5225 3200)(-4900 3200);
WIRE 16 -1 (-5675 3250)(-4900 3250);
WIRE 16 -1 (-5675 3300)(-4900 3300);
WIRE 16 -1 (-5675 3350)(-4900 3350);
WIRE 16 -1 (-5225 3400)(-4900 3400);
WIRE 16 -1 (-5225 3450)(-4900 3450);
WIRE 16 -1 (-5225 3500)(-4900 3500);
WIRE 16 -1 (-5225 3550)(-4900 3550);
WIRE 16 -1 (-5675 3600)(-4900 3600);
WIRE 16 -1 (-5675 3650)(-4900 3650);
WIRE 16 -1 (-4900 2050)(-5225 2050);
WIRE 16 -1 (-5675 2100)(-4900 2100);
WIRE 16 -1 (-5675 2150)(-4900 2150);
WIRE 16 -1 (-4900 2200)(-5225 2200);
WIRE 16 -1 (-4900 2250)(-5225 2250);
WIRE 16 -1 (-4900 2300)(-5225 2300);
WIRE 16 -1 (-5675 2350)(-4900 2350);
WIRE 16 -1 (-5675 2400)(-4900 2400);
WIRE 16 -1 (-5675 2450)(-4900 2450);
WIRE 16 -1 (-5675 2500)(-4900 2500);
WIRE 16 -1 (-5225 2550)(-4900 2550);
WIRE 16 -1 (-4900 2600)(-5225 2600);
WIRE 16 -1 (-3300 1650)(-3000 1650);
WIRE 16 -1 (-3300 1700)(-3000 1700);
WIRE 16 -1 (-2675 1750)(-3300 1750);
WIRE 16 -1 (-2675 1800)(-3300 1800);
WIRE 16 -1 (-3300 1850)(-2675 1850);
WIRE 16 -1 (-2675 1900)(-3300 1900);
WIRE 16 -1 (-3300 1950)(-3000 1950);
WIRE 16 -1 (-3300 2000)(-3000 2000);
WIRE 16 -1 (-2675 2700)(-3300 2700);
WIRE 16 -1 (-2675 2750)(-3300 2750);
WIRE 16 -1 (-3300 2800)(-3000 2800);
WIRE 16 -1 (-3000 2850)(-3300 2850);
WIRE 16 -1 (-3000 2900)(-3300 2900);
WIRE 16 -1 (-3000 2950)(-3300 2950);
WIRE 16 -1 (-2675 3000)(-3300 3000);
WIRE 16 -1 (-2675 3050)(-3300 3050);
WIRE 16 -1 (-2675 3100)(-3300 3100);
WIRE 16 -1 (-3000 3150)(-3300 3150);
WIRE 16 -1 (-3000 3200)(-3300 3200);
WIRE 16 -1 (-2675 3250)(-3300 3250);
WIRE 16 -1 (-3000 3300)(-3300 3300);
WIRE 16 -1 (-3000 3350)(-3300 3350);
WIRE 16 -1 (-3000 3400)(-3300 3400);
WIRE 16 -1 (-3000 3450)(-3300 3450);
WIRE 16 -1 (-3000 3500)(-3300 3500);
WIRE 16 -1 (-3000 3550)(-3300 3550);
WIRE 16 -1 (-2675 3600)(-3300 3600);
WIRE 16 -1 (-2675 3650)(-3300 3650);
WIRE 16 -1 (-3300 2050)(-3000 2050);
WIRE 16 -1 (-2675 2100)(-3300 2100);
WIRE 16 -1 (-2675 2150)(-3300 2150);
WIRE 16 -1 (-3300 2200)(-3000 2200);
WIRE 16 -1 (-3300 2250)(-2675 2250);
WIRE 16 -1 (-2675 2300)(-3300 2300);
WIRE 16 -1 (-2675 2350)(-3300 2350);
WIRE 16 -1 (-2675 2400)(-3300 2400);
WIRE 16 -1 (-2675 2450)(-3300 2450);
WIRE 16 -1 (-2675 2500)(-3300 2500);
WIRE 16 -1 (-3300 2550)(-3000 2550);
WIRE 16 -1 (-3300 2600)(-3000 2600);
FORCENOTE
ROOM=CPU1
(-7925 325) 0;
DISPLAY LEFT (-7925 325);
DISPLAY 1.723404 (-7925 325);
PAINT PURPLE (-7925 325);
FORCENOTE
BOM_COST=PROC_SOCKET
(-7925 200) 0;
DISPLAY LEFT (-7925 200);
DISPLAY 1.723404 (-7925 200);
PAINT PURPLE (-7925 200);
QUIT
